FILE_TYPE = MACRO_DRAWING;
SET COLOR_WIRE YELLOW;
SET COLOR_PROP ORANGE;
SET COLOR_DOT WHITE;
SET COLOR_ARC YELLOW;
SET COLOR_BODY GREEN;
SET COLOR_NOTE PURPLE;
SET PROP_DISPLAY VALUE;
SET PAGE_NUMBER P154;
FORCEADD OFFPAGE..2
(-1200 8300);
FORCEPROP 2 LAST $XR0 158 
J 0
(-1011 8300);
DISPLAY 0.638298 (-1011 8300);
PAINT MONO (-1011 8300);
FORCEPROP 1 LAST COMMENT_BODY TRUE
J 0
(-1245 8205);
DISPLAY 0.872340 (-1245 8205);
PAINT GREEN (-1245 8205);
DISPLAY INVISIBLE (-1245 8205);
FORCEPROP 1 LAST OFFPAGE TRUE
J 0
(-875 8175);
DISPLAY 0.872340 (-875 8175);
PAINT GREEN (-875 8175);
DISPLAY INVISIBLE (-875 8175);
FORCEPROP 2 LAST PATH I120
J 0
(-1000 8350);
DISPLAY 1.021277 (-1000 8350);
DISPLAY INVISIBLE (-1000 8350);
FORCEPROP 2 LAST CDS_LIB standard
J 0
(-1200 8300);
PAINT MONO (-1200 8300);
DISPLAY INVISIBLE (-1200 8300);
FORCEADD OFFPAGE..3
(-1200 8250);
FORCEPROP 2 LAST $XR0 158 
J 0
(-986 8250);
DISPLAY 0.638298 (-986 8250);
PAINT MONO (-986 8250);
FORCEPROP 2 LAST PATH I121
J 0
(-975 8300);
DISPLAY 1.021277 (-975 8300);
DISPLAY INVISIBLE (-975 8300);
FORCEPROP 2 LAST CDS_LIB standard
J 0
(-1200 8250);
PAINT MONO (-1200 8250);
DISPLAY INVISIBLE (-1200 8250);
FORCEPROP 1 LAST OFFPAGE TRUE
J 0
(-875 8125);
DISPLAY 0.872340 (-875 8125);
PAINT GREEN (-875 8125);
DISPLAY INVISIBLE (-875 8125);
FORCEPROP 1 LAST COMMENT_BODY TRUE
J 0
(-1250 8150);
DISPLAY 0.872340 (-1250 8150);
PAINT GREEN (-1250 8150);
DISPLAY INVISIBLE (-1250 8150);
FORCEADD UNIVERSAL_GND..1
(-1900 8625);
FORCEPROP 3 LASTPIN (-1900 8675) SIG_NAME GND\g
J 0
(-1890 8685);
DISPLAY 0.659574 (-1890 8685);
PAINT MONO (-1890 8685);
DISPLAY INVISIBLE (-1890 8685);
FORCEPROP 1 LAST PATH I126
J 0
(-1825 8625);
DISPLAY 0.872340 (-1825 8625);
PAINT AQUA (-1825 8625);
DISPLAY INVISIBLE (-1825 8625);
FORCEPROP 1 LAST HDL_POWER GND
J 1
(-1875 8550);
DISPLAY 0.872340 (-1875 8550);
PAINT GREEN (-1875 8550);
DISPLAY INVISIBLE (-1875 8550);
FORCEPROP 2 LAST CDS_LIB logical_power
J 0
(-1900 8625);
PAINT MONO (-1900 8625);
DISPLAY INVISIBLE (-1900 8625);
FORCEADD Q_RES..1
(-2800 8300);
FORCEPROP 1 LAST PART_NUMBER CS03322FB03
J 0
(-2950 8375);
DISPLAY 0.638298 (-2950 8375);
DISPLAY INVISIBLE (-2950 8375);
FORCEPROP 1 LAST WATTAGE 1/16W
J 2
(-2625 8425);
DISPLAY 0.638298 (-2625 8425);
FORCEPROP 1 LAST VALUE 33.2
J 2
(-2600 8300);
DISPLAY 0.510638 (-2600 8300);
FORCEPROP 1 LAST PACK_TYPE 0402LF
J 0
(-2475 8300);
DISPLAY 0.510638 (-2475 8300);
FORCEPROP 1 LAST TOLERANCE 1%
J 0
(-2575 8300);
DISPLAY 0.510638 (-2575 8300);
FORCEPROP 1 LAST MATERIAL CHIP
J 0
(-2950 8425);
DISPLAY 0.638298 (-2950 8425);
FORCEPROP 1 LAST $LOCATION R1130
J 0
(-3050 8300);
DISPLAY 0.638298 (-3050 8300);
FORCEPROP 1 LASTPIN (-2900 8300) $PN 1
J 0
(-2888 8312);
DISPLAY 0.787234 (-2888 8312);
FORCEPROP 1 LASTPIN (-2700 8300) $PN 2
J 0
(-2738 8312);
DISPLAY 0.787234 (-2738 8312);
FORCEPROP 1 LAST PATH I130
J 0
(-2850 8450);
DISPLAY 0.978723 (-2850 8450);
PAINT WHITE (-2850 8450);
DISPLAY INVISIBLE (-2850 8450);
FORCEPROP 2 LAST CDS_LIB pure_quanta
J 0
(-2800 8300);
PAINT MONO (-2800 8300);
DISPLAY INVISIBLE (-2800 8300);
FORCEPROP 2 LAST CDS_LOCATION R1130
J 0
(-2850 8500);
DISPLAY 1.021277 (-2850 8500);
DISPLAY INVISIBLE (-2850 8500);
FORCEPROP 2 LAST $SEC 1
J 0
(-2850 8500);
DISPLAY 0.680851 (-2850 8500);
PAINT MONO (-2850 8500);
DISPLAY INVISIBLE (-2850 8500);
FORCEPROP 2 LAST CDS_SEC 1
J 0
(-2850 8500);
DISPLAY 1.021277 (-2850 8500);
DISPLAY INVISIBLE (-2850 8500);
FORCEADD Q_RES..1
(-2800 8250);
FORCEPROP 1 LAST PART_NUMBER CS03322FB03
J 0
(-2925 8300);
DISPLAY 0.638298 (-2925 8300);
DISPLAY INVISIBLE (-2925 8300);
FORCEPROP 1 LAST TOLERANCE 1%
J 0
(-2575 8250);
DISPLAY 0.510638 (-2575 8250);
FORCEPROP 1 LAST PACK_TYPE 0402LF
J 0
(-2475 8250);
DISPLAY 0.510638 (-2475 8250);
FORCEPROP 1 LAST VALUE 33.2
J 2
(-2600 8250);
DISPLAY 0.510638 (-2600 8250);
FORCEPROP 1 LAST $LOCATION R1131
J 0
(-3050 8250);
DISPLAY 0.638298 (-3050 8250);
FORCEPROP 1 LASTPIN (-2900 8250) $PN 1
J 0
(-2888 8262);
DISPLAY 0.787234 (-2888 8262);
FORCEPROP 1 LASTPIN (-2700 8250) $PN 2
J 0
(-2738 8262);
DISPLAY 0.787234 (-2738 8262);
FORCEPROP 1 LAST PATH I131
J 0
(-2850 8400);
DISPLAY 0.978723 (-2850 8400);
PAINT WHITE (-2850 8400);
DISPLAY INVISIBLE (-2850 8400);
FORCEPROP 2 LAST CDS_LIB pure_quanta
J 0
(-2800 8250);
PAINT MONO (-2800 8250);
DISPLAY INVISIBLE (-2800 8250);
FORCEPROP 1 LAST WATTAGE 1/16W
J 2
(-2600 8350);
DISPLAY 0.638298 (-2600 8350);
DISPLAY INVISIBLE (-2600 8350);
FORCEPROP 1 LAST MATERIAL CHIP
J 0
(-2925 8350);
DISPLAY 0.638298 (-2925 8350);
DISPLAY INVISIBLE (-2925 8350);
FORCEPROP 2 LAST CDS_LOCATION R1131
J 0
(-2850 8450);
DISPLAY 1.021277 (-2850 8450);
DISPLAY INVISIBLE (-2850 8450);
FORCEPROP 2 LAST $SEC 1
J 0
(-2850 8450);
DISPLAY 0.680851 (-2850 8450);
PAINT MONO (-2850 8450);
DISPLAY INVISIBLE (-2850 8450);
FORCEPROP 2 LAST CDS_SEC 1
J 0
(-2850 8450);
DISPLAY 1.021277 (-2850 8450);
DISPLAY INVISIBLE (-2850 8450);
FORCEADD Q_RES..1
(-2800 8200);
FORCEPROP 1 LAST PART_NUMBER CS03322FB03
J 0
(-2925 8250);
DISPLAY 0.638298 (-2925 8250);
DISPLAY INVISIBLE (-2925 8250);
FORCEPROP 1 LAST PACK_TYPE 0402LF
J 0
(-2475 8200);
DISPLAY 0.510638 (-2475 8200);
FORCEPROP 1 LAST TOLERANCE 1%
J 0
(-2575 8200);
DISPLAY 0.510638 (-2575 8200);
FORCEPROP 1 LAST VALUE 33.2
J 2
(-2600 8200);
DISPLAY 0.510638 (-2600 8200);
FORCEPROP 1 LAST $LOCATION R1921
J 0
(-3050 8200);
DISPLAY 0.638298 (-3050 8200);
FORCEPROP 1 LASTPIN (-2900 8200) $PN 1
J 0
(-2888 8212);
DISPLAY 0.787234 (-2888 8212);
PAINT MONO (-2888 8212);
FORCEPROP 1 LASTPIN (-2700 8200) $PN 2
J 0
(-2738 8212);
DISPLAY 0.787234 (-2738 8212);
PAINT MONO (-2738 8212);
FORCEPROP 1 LAST WATTAGE 1/16W
J 2
(-2600 8300);
DISPLAY 0.638298 (-2600 8300);
DISPLAY INVISIBLE (-2600 8300);
FORCEPROP 1 LAST MATERIAL CHIP
J 0
(-2925 8300);
DISPLAY 0.638298 (-2925 8300);
DISPLAY INVISIBLE (-2925 8300);
FORCEPROP 1 LAST PATH I132
J 0
(-2850 8350);
DISPLAY 0.978723 (-2850 8350);
PAINT WHITE (-2850 8350);
DISPLAY INVISIBLE (-2850 8350);
FORCEPROP 2 LAST CDS_LIB pure_quanta
J 0
(-2800 8200);
DISPLAY INVISIBLE (-2800 8200);
FORCEPROP 0 LAST CDS_LOCATION R1921
J 0
(-3050 8250);
DISPLAY 1.021277 (-3050 8250);
DISPLAY INVISIBLE (-3050 8250);
FORCEPROP 0 LAST $SEC 1
J 0
(-3050 8250);
DISPLAY 0.680851 (-3050 8250);
PAINT MONO (-3050 8250);
DISPLAY INVISIBLE (-3050 8250);
FORCEPROP 0 LAST CDS_SEC 1
J 0
(-3050 8250);
DISPLAY 1.021277 (-3050 8250);
DISPLAY INVISIBLE (-3050 8250);
FORCEADD Q_RES..2
(-4325 9600);
FORCEPROP 1 LAST PART_NUMBER CS21002FB06
J 0
(-4285 9425);
DISPLAY 0.638298 (-4285 9425);
DISPLAY INVISIBLE (-4285 9425);
FORCEPROP 1 LAST TOLERANCE 1%
J 0
(-4280 9625);
DISPLAY 0.638298 (-4280 9625);
FORCEPROP 1 LAST VALUE 1K
J 0
(-4280 9675);
DISPLAY 0.638298 (-4280 9675);
FORCEPROP 1 LAST MATERIAL EMPTY
J 0
(-4285 9525);
DISPLAY 0.638298 (-4285 9525);
PAINT RED (-4285 9525);
FORCEPROP 1 LAST WATTAGE 1/16W
J 0
(-4285 9575);
DISPLAY 0.638298 (-4285 9575);
FORCEPROP 1 LAST PACK_TYPE 0402LF
J 0
(-4285 9475);
DISPLAY 0.638298 (-4285 9475);
FORCEPROP 1 LAST $LOCATION R1127
J 0
(-4280 9725);
DISPLAY 0.978723 (-4280 9725);
FORCEPROP 1 LASTPIN (-4325 9700) $PN 1
J 0
(-4320 9662);
DISPLAY 0.787234 (-4320 9662);
FORCEPROP 1 LASTPIN (-4325 9500) $PN 2
J 0
(-4320 9510);
DISPLAY 0.787234 (-4320 9510);
FORCEPROP 1 LAST PATH I133
J 0
(-4275 9775);
DISPLAY 0.978723 (-4275 9775);
PAINT WHITE (-4275 9775);
DISPLAY INVISIBLE (-4275 9775);
FORCEPROP 2 LAST CDS_LIB pure_quanta
J 0
(-4325 9600);
PAINT MONO (-4325 9600);
DISPLAY INVISIBLE (-4325 9600);
FORCEPROP 2 LAST CDS_LOCATION R1127
J 0
(-4275 9825);
DISPLAY 1.021277 (-4275 9825);
DISPLAY INVISIBLE (-4275 9825);
FORCEPROP 2 LAST $SEC 1
J 0
(-4275 9825);
DISPLAY 0.680851 (-4275 9825);
PAINT MONO (-4275 9825);
DISPLAY INVISIBLE (-4275 9825);
FORCEPROP 2 LAST CDS_SEC 1
J 0
(-4275 9825);
DISPLAY 1.021277 (-4275 9825);
DISPLAY INVISIBLE (-4275 9825);
FORCEADD Q_RES..2
(-4575 9600);
FORCEPROP 1 LAST PART_NUMBER CS21002FB06
J 0
(-4535 9425);
DISPLAY 0.638298 (-4535 9425);
DISPLAY INVISIBLE (-4535 9425);
FORCEPROP 1 LAST VALUE 1K
J 0
(-4530 9675);
DISPLAY 0.638298 (-4530 9675);
FORCEPROP 1 LAST TOLERANCE 1%
J 0
(-4530 9625);
DISPLAY 0.638298 (-4530 9625);
FORCEPROP 1 LAST WATTAGE 1/16W
J 0
(-4535 9575);
DISPLAY 0.638298 (-4535 9575);
FORCEPROP 1 LAST MATERIAL EMPTY
J 0
(-4535 9525);
DISPLAY 0.638298 (-4535 9525);
PAINT RED (-4535 9525);
FORCEPROP 1 LAST PACK_TYPE 0402LF
J 0
(-4535 9475);
DISPLAY 0.638298 (-4535 9475);
FORCEPROP 1 LAST $LOCATION R3037
J 0
(-4530 9725);
DISPLAY 0.978723 (-4530 9725);
FORCEPROP 1 LASTPIN (-4575 9700) $PN 1
J 0
(-4570 9662);
DISPLAY 0.787234 (-4570 9662);
FORCEPROP 1 LASTPIN (-4575 9500) $PN 2
J 0
(-4570 9510);
DISPLAY 0.787234 (-4570 9510);
FORCEPROP 1 LAST PATH I134
J 0
(-4525 9775);
DISPLAY 0.978723 (-4525 9775);
PAINT WHITE (-4525 9775);
DISPLAY INVISIBLE (-4525 9775);
FORCEPROP 2 LAST CDS_LIB pure_quanta
J 0
(-4575 9600);
PAINT MONO (-4575 9600);
DISPLAY INVISIBLE (-4575 9600);
FORCEPROP 2 LAST CDS_LOCATION R3037
J 0
(-4525 9825);
DISPLAY 1.021277 (-4525 9825);
DISPLAY INVISIBLE (-4525 9825);
FORCEPROP 2 LAST $SEC 1
J 0
(-4525 9825);
DISPLAY 0.680851 (-4525 9825);
PAINT MONO (-4525 9825);
DISPLAY INVISIBLE (-4525 9825);
FORCEPROP 2 LAST CDS_SEC 1
J 0
(-4525 9825);
DISPLAY 1.021277 (-4525 9825);
DISPLAY INVISIBLE (-4525 9825);
FORCEADD OFFPAGE..1
(-3950 8300);
FORCEPROP 2 LAST $XR0 235 
J 0
(-4232 8300);
DISPLAY 0.638298 (-4232 8300);
PAINT MONO (-4232 8300);
FORCEPROP 2 LAST PATH I135
J 0
(-4250 8350);
DISPLAY 1.021277 (-4250 8350);
DISPLAY INVISIBLE (-4250 8350);
FORCEPROP 2 LAST CDS_LIB standard
J 0
(-3950 8300);
PAINT MONO (-3950 8300);
DISPLAY INVISIBLE (-3950 8300);
FORCEPROP 1 LAST OFFPAGE TRUE
J 0
(-3625 8175);
DISPLAY 0.872340 (-3625 8175);
PAINT GREEN (-3625 8175);
DISPLAY INVISIBLE (-3625 8175);
FORCEPROP 1 LAST COMMENT_BODY TRUE
J 0
(-3825 8200);
DISPLAY 0.872340 (-3825 8200);
PAINT GREEN (-3825 8200);
DISPLAY INVISIBLE (-3825 8200);
FORCEADD OFFPAGE..3
R 2
(-3950 8250);
FORCEPROP 2 LAST $XR0 235 
J 0
(-4260 8250);
DISPLAY 0.638298 (-4260 8250);
PAINT MONO (-4260 8250);
FORCEPROP 2 LAST PATH I136
J 0
(-4275 8300);
DISPLAY 1.021277 (-4275 8300);
DISPLAY INVISIBLE (-4275 8300);
FORCEPROP 1 LAST OFFPAGE TRUE
J 2
(-4275 8125);
DISPLAY 0.872340 (-4275 8125);
DISPLAY INVISIBLE (-4275 8125);
FORCEPROP 1 LAST COMMENT_BODY TRUE
J 2
(-3900 8150);
DISPLAY 0.872340 (-3900 8150);
PAINT GREEN (-3900 8150);
DISPLAY INVISIBLE (-3900 8150);
FORCEPROP 2 LAST CDS_LIB standard
J 0
(-3950 8250);
PAINT MONO (-3950 8250);
DISPLAY INVISIBLE (-3950 8250);
FORCEADD Q_RES..2
(-4325 9000);
FORCEPROP 1 LAST PART_NUMBER CS21002FB06
J 0
(-4285 8825);
DISPLAY 0.638298 (-4285 8825);
DISPLAY INVISIBLE (-4285 8825);
FORCEPROP 1 LAST PACK_TYPE 0402LF
J 0
(-4285 8875);
DISPLAY 0.638298 (-4285 8875);
FORCEPROP 1 LAST TOLERANCE 1%
J 0
(-4280 9025);
DISPLAY 0.638298 (-4280 9025);
FORCEPROP 1 LAST MATERIAL CHIP
J 0
(-4285 8925);
DISPLAY 0.638298 (-4285 8925);
FORCEPROP 1 LAST WATTAGE 1/16W
J 0
(-4285 8975);
DISPLAY 0.638298 (-4285 8975);
FORCEPROP 1 LAST VALUE 1K
J 0
(-4280 9075);
DISPLAY 0.638298 (-4280 9075);
FORCEPROP 1 LAST $LOCATION R1128
J 0
(-4280 9125);
DISPLAY 0.978723 (-4280 9125);
FORCEPROP 1 LASTPIN (-4325 9100) $PN 1
J 0
(-4320 9062);
DISPLAY 0.787234 (-4320 9062);
FORCEPROP 1 LASTPIN (-4325 8900) $PN 2
J 0
(-4320 8910);
DISPLAY 0.787234 (-4320 8910);
FORCEPROP 1 LAST PATH I137
J 0
(-4275 9175);
DISPLAY 0.978723 (-4275 9175);
PAINT WHITE (-4275 9175);
DISPLAY INVISIBLE (-4275 9175);
FORCEPROP 2 LAST CDS_LIB pure_quanta
J 0
(-4325 9000);
PAINT MONO (-4325 9000);
DISPLAY INVISIBLE (-4325 9000);
FORCEPROP 2 LAST CDS_LOCATION R1128
J 0
(-4275 9225);
DISPLAY 1.021277 (-4275 9225);
DISPLAY INVISIBLE (-4275 9225);
FORCEPROP 2 LAST $SEC 1
J 0
(-4275 9225);
DISPLAY 0.680851 (-4275 9225);
PAINT MONO (-4275 9225);
DISPLAY INVISIBLE (-4275 9225);
FORCEPROP 2 LAST CDS_SEC 1
J 0
(-4275 9225);
DISPLAY 1.021277 (-4275 9225);
DISPLAY INVISIBLE (-4275 9225);
FORCEADD UNIVERSAL_GND..1
(-4325 8775);
FORCEPROP 3 LASTPIN (-4325 8825) SIG_NAME GND\g
J 0
(-4315 8835);
DISPLAY 0.659574 (-4315 8835);
PAINT MONO (-4315 8835);
DISPLAY INVISIBLE (-4315 8835);
FORCEPROP 1 LAST PATH I138
J 0
(-4250 8775);
DISPLAY 0.872340 (-4250 8775);
PAINT AQUA (-4250 8775);
DISPLAY INVISIBLE (-4250 8775);
FORCEPROP 2 LAST CDS_LIB logical_power
J 0
(-4325 8775);
PAINT MONO (-4325 8775);
DISPLAY INVISIBLE (-4325 8775);
FORCEPROP 1 LAST HDL_POWER GND
J 1
(-4300 8700);
DISPLAY 0.872340 (-4300 8700);
PAINT GREEN (-4300 8700);
DISPLAY INVISIBLE (-4300 8700);
FORCEADD UNIVERSAL_GND..1
(-4575 8775);
FORCEPROP 3 LASTPIN (-4575 8825) SIG_NAME GND\g
J 0
(-4565 8835);
DISPLAY 0.659574 (-4565 8835);
PAINT MONO (-4565 8835);
DISPLAY INVISIBLE (-4565 8835);
FORCEPROP 1 LAST PATH I139
J 0
(-4500 8775);
DISPLAY 0.872340 (-4500 8775);
PAINT AQUA (-4500 8775);
DISPLAY INVISIBLE (-4500 8775);
FORCEPROP 2 LAST CDS_LIB logical_power
J 0
(-4575 8775);
PAINT MONO (-4575 8775);
DISPLAY INVISIBLE (-4575 8775);
FORCEPROP 1 LAST HDL_POWER GND
J 1
(-4550 8700);
DISPLAY 0.872340 (-4550 8700);
PAINT GREEN (-4550 8700);
DISPLAY INVISIBLE (-4550 8700);
FORCEADD Q_RES..2
(-4575 9000);
FORCEPROP 1 LAST PART_NUMBER CS21002FB06
J 0
(-4535 8825);
DISPLAY 0.638298 (-4535 8825);
DISPLAY INVISIBLE (-4535 8825);
FORCEPROP 1 LAST PACK_TYPE 0402LF
J 0
(-4535 8875);
DISPLAY 0.638298 (-4535 8875);
FORCEPROP 1 LAST MATERIAL CHIP
J 0
(-4535 8925);
DISPLAY 0.638298 (-4535 8925);
FORCEPROP 1 LAST TOLERANCE 1%
J 0
(-4530 9025);
DISPLAY 0.638298 (-4530 9025);
FORCEPROP 1 LAST VALUE 1K
J 0
(-4530 9075);
DISPLAY 0.638298 (-4530 9075);
FORCEPROP 1 LAST WATTAGE 1/16W
J 0
(-4535 8975);
DISPLAY 0.638298 (-4535 8975);
FORCEPROP 1 LAST $LOCATION R1126
J 0
(-4530 9125);
DISPLAY 0.978723 (-4530 9125);
FORCEPROP 1 LASTPIN (-4575 9100) $PN 1
J 0
(-4570 9062);
DISPLAY 0.787234 (-4570 9062);
FORCEPROP 1 LASTPIN (-4575 8900) $PN 2
J 0
(-4570 8910);
DISPLAY 0.787234 (-4570 8910);
FORCEPROP 1 LAST PATH I140
J 0
(-4525 9175);
DISPLAY 0.978723 (-4525 9175);
PAINT WHITE (-4525 9175);
DISPLAY INVISIBLE (-4525 9175);
FORCEPROP 2 LAST CDS_LIB pure_quanta
J 0
(-4575 9000);
PAINT MONO (-4575 9000);
DISPLAY INVISIBLE (-4575 9000);
FORCEPROP 2 LAST CDS_LOCATION R1126
J 0
(-4525 9225);
DISPLAY 1.021277 (-4525 9225);
DISPLAY INVISIBLE (-4525 9225);
FORCEPROP 2 LAST $SEC 1
J 0
(-4525 9225);
DISPLAY 0.680851 (-4525 9225);
PAINT MONO (-4525 9225);
DISPLAY INVISIBLE (-4525 9225);
FORCEPROP 2 LAST CDS_SEC 1
J 0
(-4525 9225);
DISPLAY 1.021277 (-4525 9225);
DISPLAY INVISIBLE (-4525 9225);
FORCEADD UNIVERSAL_POWER..1
(-4825 10000);
FORCEPROP 3 LASTPIN (-4825 9950) SIG_NAME P3V3_AUX\g
J 0
(-4815 9960);
DISPLAY 0.659574 (-4815 9960);
PAINT MONO (-4815 9960);
DISPLAY INVISIBLE (-4815 9960);
FORCEPROP 1 LAST HDL_POWER P3V3_AUX
J 1
(-4825 10050);
DISPLAY 0.872340 (-4825 10050);
PAINT GREEN (-4825 10050);
FORCEPROP 1 LAST PATH I141
J 0
(-4775 10025);
DISPLAY 0.872340 (-4775 10025);
PAINT AQUA (-4775 10025);
DISPLAY INVISIBLE (-4775 10025);
FORCEPROP 2 LAST CDS_LIB logical_power
J 0
(-4825 10000);
PAINT MONO (-4825 10000);
DISPLAY INVISIBLE (-4825 10000);
FORCEADD Q_RES..2
(-4825 9600);
FORCEPROP 1 LAST PART_NUMBER CS21002FB06
J 0
(-4785 9425);
DISPLAY 0.638298 (-4785 9425);
DISPLAY INVISIBLE (-4785 9425);
FORCEPROP 1 LAST TOLERANCE 1%
J 0
(-4780 9625);
DISPLAY 0.638298 (-4780 9625);
FORCEPROP 1 LAST VALUE 1K
J 0
(-4780 9675);
DISPLAY 0.638298 (-4780 9675);
FORCEPROP 1 LAST WATTAGE 1/16W
J 0
(-4785 9575);
DISPLAY 0.638298 (-4785 9575);
FORCEPROP 1 LAST MATERIAL EMPTY
J 0
(-4785 9525);
DISPLAY 0.638298 (-4785 9525);
PAINT RED (-4785 9525);
FORCEPROP 1 LAST PACK_TYPE 0402LF
J 0
(-4785 9475);
DISPLAY 0.638298 (-4785 9475);
FORCEPROP 1 LAST $LOCATION R1123
J 0
(-4780 9725);
DISPLAY 0.978723 (-4780 9725);
FORCEPROP 1 LASTPIN (-4825 9700) $PN 1
J 0
(-4820 9662);
DISPLAY 0.787234 (-4820 9662);
FORCEPROP 1 LASTPIN (-4825 9500) $PN 2
J 0
(-4820 9510);
DISPLAY 0.787234 (-4820 9510);
FORCEPROP 1 LAST PATH I142
J 0
(-4775 9775);
DISPLAY 0.978723 (-4775 9775);
PAINT WHITE (-4775 9775);
DISPLAY INVISIBLE (-4775 9775);
FORCEPROP 2 LAST CDS_LIB pure_quanta
J 0
(-4825 9600);
PAINT MONO (-4825 9600);
DISPLAY INVISIBLE (-4825 9600);
FORCEPROP 2 LAST CDS_LOCATION R1123
J 0
(-4775 9825);
DISPLAY 1.021277 (-4775 9825);
DISPLAY INVISIBLE (-4775 9825);
FORCEPROP 2 LAST $SEC 1
J 0
(-4775 9825);
DISPLAY 0.680851 (-4775 9825);
PAINT MONO (-4775 9825);
DISPLAY INVISIBLE (-4775 9825);
FORCEPROP 2 LAST CDS_SEC 1
J 0
(-4775 9825);
DISPLAY 1.021277 (-4775 9825);
DISPLAY INVISIBLE (-4775 9825);
FORCEADD Q_RES..2
(-4825 9000);
FORCEPROP 1 LAST PART_NUMBER CS21002FB06
J 0
(-4785 8825);
DISPLAY 0.638298 (-4785 8825);
DISPLAY INVISIBLE (-4785 8825);
FORCEPROP 1 LAST TOLERANCE 1%
J 0
(-4780 9025);
DISPLAY 0.638298 (-4780 9025);
FORCEPROP 1 LAST PACK_TYPE 0402LF
J 0
(-4785 8875);
DISPLAY 0.638298 (-4785 8875);
FORCEPROP 1 LAST WATTAGE 1/16W
J 0
(-4785 8975);
DISPLAY 0.638298 (-4785 8975);
FORCEPROP 1 LAST MATERIAL CHIP
J 0
(-4785 8925);
DISPLAY 0.638298 (-4785 8925);
FORCEPROP 1 LAST VALUE 1K
J 0
(-4780 9075);
DISPLAY 0.638298 (-4780 9075);
FORCEPROP 1 LAST $LOCATION R1124
J 0
(-4780 9125);
DISPLAY 0.978723 (-4780 9125);
FORCEPROP 1 LASTPIN (-4825 9100) $PN 1
J 0
(-4820 9062);
DISPLAY 0.787234 (-4820 9062);
FORCEPROP 1 LASTPIN (-4825 8900) $PN 2
J 0
(-4820 8910);
DISPLAY 0.787234 (-4820 8910);
FORCEPROP 1 LAST PATH I143
J 0
(-4775 9175);
DISPLAY 0.978723 (-4775 9175);
PAINT WHITE (-4775 9175);
DISPLAY INVISIBLE (-4775 9175);
FORCEPROP 2 LAST CDS_LIB pure_quanta
J 0
(-4825 9000);
PAINT MONO (-4825 9000);
DISPLAY INVISIBLE (-4825 9000);
FORCEPROP 2 LAST CDS_LOCATION R1124
J 0
(-4775 9225);
DISPLAY 1.021277 (-4775 9225);
DISPLAY INVISIBLE (-4775 9225);
FORCEPROP 2 LAST $SEC 1
J 0
(-4775 9225);
DISPLAY 0.680851 (-4775 9225);
PAINT MONO (-4775 9225);
DISPLAY INVISIBLE (-4775 9225);
FORCEPROP 2 LAST CDS_SEC 1
J 0
(-4775 9225);
DISPLAY 1.021277 (-4775 9225);
DISPLAY INVISIBLE (-4775 9225);
FORCEADD UNIVERSAL_GND..1
(-4825 8775);
FORCEPROP 3 LASTPIN (-4825 8825) SIG_NAME GND\g
J 0
(-4815 8835);
DISPLAY 0.659574 (-4815 8835);
PAINT MONO (-4815 8835);
DISPLAY INVISIBLE (-4815 8835);
FORCEPROP 1 LAST PATH I144
J 0
(-4750 8775);
DISPLAY 0.872340 (-4750 8775);
PAINT AQUA (-4750 8775);
DISPLAY INVISIBLE (-4750 8775);
FORCEPROP 2 LAST CDS_LIB logical_power
J 0
(-4825 8775);
PAINT MONO (-4825 8775);
DISPLAY INVISIBLE (-4825 8775);
FORCEPROP 1 LAST HDL_POWER GND
J 1
(-4800 8700);
DISPLAY 0.872340 (-4800 8700);
PAINT GREEN (-4800 8700);
DISPLAY INVISIBLE (-4800 8700);
FORCEADD UNIVERSAL_POWER..1
(3175 7525);
FORCEPROP 3 LASTPIN (3175 7475) SIG_NAME P3V3_AUX\g
J 0
(3185 7485);
DISPLAY 0.659574 (3185 7485);
PAINT MONO (3185 7485);
DISPLAY INVISIBLE (3185 7485);
FORCEPROP 1 LAST HDL_POWER P3V3_AUX
J 1
(3175 7575);
DISPLAY 0.872340 (3175 7575);
PAINT GREEN (3175 7575);
FORCEPROP 2 LAST CDS_LIB logical_power
J 0
(3175 7525);
PAINT MONO (3175 7525);
DISPLAY INVISIBLE (3175 7525);
FORCEPROP 1 LAST PATH I145
J 0
(3225 7550);
DISPLAY 0.872340 (3225 7550);
PAINT AQUA (3225 7550);
DISPLAY INVISIBLE (3225 7550);
FORCEADD OFFPAGE..2
(3500 6925);
FORCEPROP 2 LAST $XR0 155 
J 0
(3689 6925);
DISPLAY 0.638298 (3689 6925);
PAINT MONO (3689 6925);
FORCEPROP 2 LAST CDS_LIB standard
J 0
(3500 6925);
PAINT MONO (3500 6925);
DISPLAY INVISIBLE (3500 6925);
FORCEPROP 2 LAST PATH I146
J 0
(3700 6975);
DISPLAY 1.021277 (3700 6975);
DISPLAY INVISIBLE (3700 6975);
FORCEPROP 1 LAST COMMENT_BODY TRUE
J 0
(3455 6830);
DISPLAY 0.872340 (3455 6830);
PAINT GREEN (3455 6830);
DISPLAY INVISIBLE (3455 6830);
FORCEPROP 1 LAST OFFPAGE TRUE
J 0
(3825 6800);
DISPLAY 0.872340 (3825 6800);
PAINT GREEN (3825 6800);
DISPLAY INVISIBLE (3825 6800);
FORCEADD Q_CAP..1
(3175 7250);
FORCEPROP 1 LAST PART_NUMBER CH4104K1B00
J 0
(3225 7100);
DISPLAY 0.510638 (3225 7100);
DISPLAY INVISIBLE (3225 7100);
FORCEPROP 1 LAST PACK_TYPE 0402
J 0
(3225 7050);
DISPLAY 0.510638 (3225 7050);
FORCEPROP 1 LAST VALUE 0.1UF
J 0
(3225 7300);
DISPLAY 0.510638 (3225 7300);
FORCEPROP 1 LAST VOLTAGE 25V
J 0
(3225 7250);
DISPLAY 0.510638 (3225 7250);
FORCEPROP 1 LAST TOLERANCE 10%
J 0
(3225 7200);
DISPLAY 0.510638 (3225 7200);
FORCEPROP 1 LAST MATERIAL X7R
J 0
(3225 7150);
DISPLAY 0.510638 (3225 7150);
FORCEPROP 1 LAST $LOCATION C581
J 0
(3225 7350);
DISPLAY 0.978723 (3225 7350);
FORCEPROP 1 LASTPIN (3175 7350) $PN 1
J 0
(3185 7330);
DISPLAY 0.787234 (3185 7330);
FORCEPROP 1 LASTPIN (3175 7150) $PN 2
J 0
(3185 7130);
DISPLAY 0.787234 (3185 7130);
FORCEPROP 2 LAST CDS_LIB pure_quanta
J 2
(3175 7250);
PAINT MONO (3175 7250);
DISPLAY INVISIBLE (3175 7250);
FORCEPROP 1 LAST PATH I148
J 0
(3225 7400);
DISPLAY 0.978723 (3225 7400);
PAINT WHITE (3225 7400);
DISPLAY INVISIBLE (3225 7400);
FORCEPROP 2 LAST CDS_LOCATION C581
J 0
(3225 7450);
DISPLAY 1.021277 (3225 7450);
DISPLAY INVISIBLE (3225 7450);
FORCEPROP 2 LAST $SEC 1
J 0
(3225 7450);
DISPLAY 0.680851 (3225 7450);
PAINT MONO (3225 7450);
DISPLAY INVISIBLE (3225 7450);
FORCEPROP 2 LAST CDS_SEC 1
J 0
(3225 7450);
DISPLAY 1.021277 (3225 7450);
DISPLAY INVISIBLE (3225 7450);
FORCEADD UNIVERSAL_GND..1
(3175 7025);
FORCEPROP 3 LASTPIN (3175 7075) SIG_NAME GND\g
J 0
(3185 7085);
DISPLAY 0.659574 (3185 7085);
PAINT MONO (3185 7085);
DISPLAY INVISIBLE (3185 7085);
FORCEPROP 2 LAST CDS_LIB logical_power
J 0
(3175 7025);
PAINT MONO (3175 7025);
DISPLAY INVISIBLE (3175 7025);
FORCEPROP 1 LAST HDL_POWER GND
J 1
(3200 6950);
DISPLAY 0.872340 (3200 6950);
PAINT GREEN (3200 6950);
DISPLAY INVISIBLE (3200 6950);
FORCEPROP 1 LAST PATH I149
J 0
(3250 7025);
DISPLAY 0.872340 (3250 7025);
PAINT AQUA (3250 7025);
DISPLAY INVISIBLE (3250 7025);
FORCEADD UNIVERSAL_GND..1
(2050 6750);
FORCEPROP 3 LASTPIN (2050 6800) SIG_NAME GND\g
J 0
(2060 6810);
DISPLAY 0.659574 (2060 6810);
PAINT MONO (2060 6810);
DISPLAY INVISIBLE (2060 6810);
FORCEPROP 1 LAST PATH I151
J 0
(2125 6750);
DISPLAY 0.872340 (2125 6750);
PAINT AQUA (2125 6750);
DISPLAY INVISIBLE (2125 6750);
FORCEPROP 2 LAST CDS_LIB logical_power
J 0
(2050 6750);
PAINT MONO (2050 6750);
DISPLAY INVISIBLE (2050 6750);
FORCEPROP 1 LAST HDL_POWER GND
J 1
(2075 6675);
DISPLAY 0.872340 (2075 6675);
PAINT GREEN (2075 6675);
DISPLAY INVISIBLE (2075 6675);
FORCEADD OFFPAGE..1
(975 6975);
FORCEPROP 2 LAST $XR0 223 
J 0
(723 6975);
DISPLAY 0.638298 (723 6975);
PAINT MONO (723 6975);
FORCEPROP 2 LAST CDS_LIB standard
J 0
(975 6975);
PAINT MONO (975 6975);
DISPLAY INVISIBLE (975 6975);
FORCEPROP 1 LAST COMMENT_BODY TRUE
J 0
(1100 6875);
DISPLAY 0.872340 (1100 6875);
PAINT GREEN (1100 6875);
DISPLAY INVISIBLE (1100 6875);
FORCEPROP 1 LAST OFFPAGE TRUE
J 0
(1300 6850);
DISPLAY 0.872340 (1300 6850);
PAINT GREEN (1300 6850);
DISPLAY INVISIBLE (1300 6850);
FORCEPROP 2 LAST PATH I156
J 0
(700 7025);
DISPLAY 1.021277 (700 7025);
DISPLAY INVISIBLE (700 7025);
FORCEADD OFFPAGE..2
(-1200 8200);
FORCEPROP 2 LAST $XR0 235 
J 0
(-981 8200);
DISPLAY 0.638298 (-981 8200);
PAINT MONO (-981 8200);
FORCEPROP 2 LAST PATH I163
J 0
(-850 8250);
DISPLAY 1.021277 (-850 8250);
DISPLAY INVISIBLE (-850 8250);
FORCEPROP 1 LAST COMMENT_BODY TRUE
J 0
(-1245 8105);
DISPLAY 0.872340 (-1245 8105);
PAINT GREEN (-1245 8105);
DISPLAY INVISIBLE (-1245 8105);
FORCEPROP 1 LAST OFFPAGE TRUE
J 0
(-875 8075);
DISPLAY 0.872340 (-875 8075);
PAINT GREEN (-875 8075);
DISPLAY INVISIBLE (-875 8075);
FORCEPROP 2 LAST CDS_LIB standard
J 0
(-1200 8200);
DISPLAY INVISIBLE (-1200 8200);
FORCEADD OFFPAGE..2
(-1850 5075);
FORCEPROP 2 LAST $XR2 238 
J 0
(-1421 5075);
DISPLAY 0.638298 (-1421 5075);
PAINT MONO (-1421 5075);
FORCEPROP 2 LAST $XR1 157 
J 0
(-1541 5075);
DISPLAY 0.638298 (-1541 5075);
PAINT MONO (-1541 5075);
FORCEPROP 2 LAST $XR0 156 
J 0
(-1661 5075);
DISPLAY 0.638298 (-1661 5075);
PAINT MONO (-1661 5075);
FORCEPROP 1 LAST COMMENT_BODY TRUE
J 0
(-1895 4980);
DISPLAY 0.872340 (-1895 4980);
PAINT GREEN (-1895 4980);
DISPLAY INVISIBLE (-1895 4980);
FORCEPROP 1 LAST OFFPAGE TRUE
J 0
(-1525 4950);
DISPLAY 0.872340 (-1525 4950);
PAINT GREEN (-1525 4950);
DISPLAY INVISIBLE (-1525 4950);
FORCEPROP 2 LAST PATH I166
J 0
(-1650 5125);
DISPLAY 1.021277 (-1650 5125);
DISPLAY INVISIBLE (-1650 5125);
FORCEPROP 2 LAST CDS_LIB standard
J 0
(-1850 5075);
PAINT MONO (-1850 5075);
DISPLAY INVISIBLE (-1850 5075);
FORCEADD OFFPAGE..1
(-1200 7125);
FORCEPROP 2 LAST $XR2 214 
J 0
(-1692 7125);
DISPLAY 0.638298 (-1692 7125);
PAINT MONO (-1692 7125);
FORCEPROP 2 LAST $XR1 157 
J 0
(-1572 7125);
DISPLAY 0.638298 (-1572 7125);
PAINT MONO (-1572 7125);
FORCEPROP 2 LAST $XR0 156 
J 0
(-1452 7125);
DISPLAY 0.638298 (-1452 7125);
PAINT MONO (-1452 7125);
FORCEPROP 2 LAST CDS_LIB standard
J 0
(-1200 7125);
PAINT MONO (-1200 7125);
DISPLAY INVISIBLE (-1200 7125);
FORCEPROP 2 LAST PATH I167
J 0
(-1475 7175);
DISPLAY 1.021277 (-1475 7175);
DISPLAY INVISIBLE (-1475 7175);
FORCEPROP 1 LAST COMMENT_BODY TRUE
J 0
(-1075 7025);
DISPLAY 0.872340 (-1075 7025);
PAINT GREEN (-1075 7025);
DISPLAY INVISIBLE (-1075 7025);
FORCEPROP 1 LAST OFFPAGE TRUE
J 0
(-875 7000);
DISPLAY 0.872340 (-875 7000);
PAINT GREEN (-875 7000);
DISPLAY INVISIBLE (-875 7000);
FORCEADD UNIVERSAL_POWER..1
(-2350 5775);
FORCEPROP 3 LASTPIN (-2350 5725) SIG_NAME P3V3_AUX\g
J 0
(-2340 5735);
DISPLAY 0.659574 (-2340 5735);
PAINT MONO (-2340 5735);
DISPLAY INVISIBLE (-2340 5735);
FORCEPROP 1 LAST HDL_POWER P3V3_AUX
J 1
(-2350 5825);
DISPLAY 0.872340 (-2350 5825);
PAINT GREEN (-2350 5825);
FORCEPROP 1 LAST PATH I168
J 0
(-2300 5800);
DISPLAY 0.872340 (-2300 5800);
PAINT AQUA (-2300 5800);
DISPLAY INVISIBLE (-2300 5800);
FORCEPROP 2 LAST CDS_LIB logical_power
J 0
(-2350 5775);
PAINT MONO (-2350 5775);
DISPLAY INVISIBLE (-2350 5775);
FORCEADD Q_CAP..1
(-2350 5500);
FORCEPROP 1 LAST PART_NUMBER CH4104K1B00
J 0
(-2300 5350);
DISPLAY 0.510638 (-2300 5350);
DISPLAY INVISIBLE (-2300 5350);
FORCEPROP 1 LAST PACK_TYPE 0402
J 0
(-2300 5300);
DISPLAY 0.510638 (-2300 5300);
FORCEPROP 1 LAST MATERIAL X7R
J 0
(-2300 5400);
DISPLAY 0.510638 (-2300 5400);
FORCEPROP 1 LAST VALUE 0.1UF
J 0
(-2300 5550);
DISPLAY 0.510638 (-2300 5550);
FORCEPROP 1 LAST TOLERANCE 10%
J 0
(-2300 5450);
DISPLAY 0.510638 (-2300 5450);
FORCEPROP 1 LAST VOLTAGE 25V
J 0
(-2300 5500);
DISPLAY 0.510638 (-2300 5500);
FORCEPROP 1 LAST $LOCATION C578
J 0
(-2300 5600);
DISPLAY 0.978723 (-2300 5600);
FORCEPROP 1 LASTPIN (-2350 5600) $PN 1
J 0
(-2340 5580);
DISPLAY 0.787234 (-2340 5580);
FORCEPROP 1 LASTPIN (-2350 5400) $PN 2
J 0
(-2340 5380);
DISPLAY 0.787234 (-2340 5380);
FORCEPROP 1 LAST PATH I169
J 0
(-2300 5650);
DISPLAY 0.978723 (-2300 5650);
PAINT WHITE (-2300 5650);
DISPLAY INVISIBLE (-2300 5650);
FORCEPROP 2 LAST CDS_LIB pure_quanta
J 2
(-2350 5500);
PAINT MONO (-2350 5500);
DISPLAY INVISIBLE (-2350 5500);
FORCEPROP 2 LAST CDS_LOCATION C578
J 0
(-2300 5700);
DISPLAY 1.021277 (-2300 5700);
DISPLAY INVISIBLE (-2300 5700);
FORCEPROP 2 LAST $SEC 1
J 0
(-2300 5700);
DISPLAY 0.680851 (-2300 5700);
PAINT MONO (-2300 5700);
DISPLAY INVISIBLE (-2300 5700);
FORCEPROP 2 LAST CDS_SEC 1
J 0
(-2300 5700);
DISPLAY 1.021277 (-2300 5700);
DISPLAY INVISIBLE (-2300 5700);
FORCEADD UNIVERSAL_GND..1
(-2350 5275);
FORCEPROP 3 LASTPIN (-2350 5325) SIG_NAME GND\g
J 0
(-2340 5335);
DISPLAY 0.659574 (-2340 5335);
PAINT MONO (-2340 5335);
DISPLAY INVISIBLE (-2340 5335);
FORCEPROP 1 LAST PATH I170
J 0
(-2275 5275);
DISPLAY 0.872340 (-2275 5275);
PAINT AQUA (-2275 5275);
DISPLAY INVISIBLE (-2275 5275);
FORCEPROP 1 LAST HDL_POWER GND
J 1
(-2325 5200);
DISPLAY 0.872340 (-2325 5200);
PAINT GREEN (-2325 5200);
DISPLAY INVISIBLE (-2325 5200);
FORCEPROP 2 LAST CDS_LIB logical_power
J 0
(-2350 5275);
PAINT MONO (-2350 5275);
DISPLAY INVISIBLE (-2350 5275);
FORCEADD UNIVERSAL_POWER..1
(-4000 5725);
FORCEPROP 3 LASTPIN (-4000 5675) SIG_NAME P3V3_AUX\g
J 0
(-3990 5685);
DISPLAY 0.659574 (-3990 5685);
PAINT MONO (-3990 5685);
DISPLAY INVISIBLE (-3990 5685);
FORCEPROP 1 LAST HDL_POWER P3V3_AUX
J 1
(-4000 5775);
DISPLAY 0.872340 (-4000 5775);
PAINT GREEN (-4000 5775);
FORCEPROP 2 LAST CDS_LIB logical_power
J 0
(-4000 5725);
PAINT MONO (-4000 5725);
DISPLAY INVISIBLE (-4000 5725);
FORCEPROP 1 LAST PATH I171
J 0
(-3950 5750);
DISPLAY 0.872340 (-3950 5750);
PAINT AQUA (-3950 5750);
DISPLAY INVISIBLE (-3950 5750);
FORCEADD Q_RES..2
(-4000 5450);
FORCEPROP 1 LAST PART_NUMBER CS21002FB06
J 0
(-3960 5275);
DISPLAY 0.638298 (-3960 5275);
DISPLAY INVISIBLE (-3960 5275);
FORCEPROP 1 LAST TOLERANCE 1%
J 0
(-3955 5475);
DISPLAY 0.638298 (-3955 5475);
FORCEPROP 1 LAST WATTAGE 1/16W
J 0
(-3960 5425);
DISPLAY 0.638298 (-3960 5425);
FORCEPROP 1 LAST MATERIAL CHIP
J 0
(-3960 5375);
DISPLAY 0.638298 (-3960 5375);
FORCEPROP 1 LAST VALUE 1K
J 0
(-3955 5525);
DISPLAY 0.638298 (-3955 5525);
FORCEPROP 1 LAST PACK_TYPE 0402LF
J 0
(-3960 5325);
DISPLAY 0.638298 (-3960 5325);
FORCEPROP 1 LAST $LOCATION R1129
J 0
(-3955 5575);
DISPLAY 0.978723 (-3955 5575);
FORCEPROP 1 LASTPIN (-4000 5550) $PN 1
J 0
(-3995 5512);
DISPLAY 0.787234 (-3995 5512);
FORCEPROP 1 LASTPIN (-4000 5350) $PN 2
J 0
(-3995 5360);
DISPLAY 0.787234 (-3995 5360);
FORCEPROP 2 LAST CDS_LIB pure_quanta
J 0
(-4000 5450);
PAINT MONO (-4000 5450);
DISPLAY INVISIBLE (-4000 5450);
FORCEPROP 1 LAST PATH I172
J 0
(-3950 5625);
DISPLAY 0.978723 (-3950 5625);
PAINT WHITE (-3950 5625);
DISPLAY INVISIBLE (-3950 5625);
FORCEPROP 2 LAST CDS_LOCATION R1129
J 0
(-3950 5675);
DISPLAY 1.021277 (-3950 5675);
DISPLAY INVISIBLE (-3950 5675);
FORCEPROP 2 LAST $SEC 1
J 0
(-3950 5675);
DISPLAY 0.680851 (-3950 5675);
PAINT MONO (-3950 5675);
DISPLAY INVISIBLE (-3950 5675);
FORCEPROP 2 LAST CDS_SEC 1
J 0
(-3950 5675);
DISPLAY 1.021277 (-3950 5675);
DISPLAY INVISIBLE (-3950 5675);
FORCEADD OFFPAGE..1
(-3700 5225);
FORCEPROP 2 LAST $XR0 158 
J 0
(-3952 5225);
DISPLAY 0.638298 (-3952 5225);
PAINT MONO (-3952 5225);
FORCEPROP 1 LAST OFFPAGE TRUE
J 0
(-3375 5100);
DISPLAY 0.872340 (-3375 5100);
PAINT GREEN (-3375 5100);
DISPLAY INVISIBLE (-3375 5100);
FORCEPROP 1 LAST COMMENT_BODY TRUE
J 0
(-3575 5125);
DISPLAY 0.872340 (-3575 5125);
PAINT GREEN (-3575 5125);
DISPLAY INVISIBLE (-3575 5125);
FORCEPROP 2 LAST CDS_LIB standard
J 0
(-3700 5225);
PAINT MONO (-3700 5225);
DISPLAY INVISIBLE (-3700 5225);
FORCEPROP 2 LAST PATH I173
J 0
(-3975 5275);
DISPLAY 1.021277 (-3975 5275);
DISPLAY INVISIBLE (-3975 5275);
FORCEADD UNIVERSAL_GND..1
(-3225 4900);
FORCEPROP 3 LASTPIN (-3225 4950) SIG_NAME GND\g
J 0
(-3215 4960);
DISPLAY 0.659574 (-3215 4960);
PAINT MONO (-3215 4960);
DISPLAY INVISIBLE (-3215 4960);
FORCEPROP 1 LAST PATH I174
J 0
(-3150 4900);
DISPLAY 0.872340 (-3150 4900);
PAINT AQUA (-3150 4900);
DISPLAY INVISIBLE (-3150 4900);
FORCEPROP 1 LAST HDL_POWER GND
J 1
(-3200 4825);
DISPLAY 0.872340 (-3200 4825);
PAINT GREEN (-3200 4825);
DISPLAY INVISIBLE (-3200 4825);
FORCEPROP 2 LAST CDS_LIB logical_power
J 0
(-3225 4900);
PAINT MONO (-3225 4900);
DISPLAY INVISIBLE (-3225 4900);
FORCEADD UNIVERSAL_GND..1
(-4000 4525);
FORCEPROP 3 LASTPIN (-4000 4575) SIG_NAME GND\g
J 0
(-3990 4585);
DISPLAY 0.659574 (-3990 4585);
PAINT MONO (-3990 4585);
DISPLAY INVISIBLE (-3990 4585);
FORCEPROP 1 LAST HDL_POWER GND
J 1
(-3975 4450);
DISPLAY 0.872340 (-3975 4450);
PAINT GREEN (-3975 4450);
DISPLAY INVISIBLE (-3975 4450);
FORCEPROP 2 LAST CDS_LIB logical_power
J 0
(-4000 4525);
PAINT MONO (-4000 4525);
DISPLAY INVISIBLE (-4000 4525);
FORCEPROP 1 LAST PATH I176
J 0
(-3925 4525);
DISPLAY 0.872340 (-3925 4525);
PAINT AQUA (-3925 4525);
DISPLAY INVISIBLE (-3925 4525);
FORCEADD MOSFET_N..1
(-4050 4900);
FORCEPROP 1 LAST PART_NUMBER BAM138K0000
J 0
(-3928 4786);
DISPLAY 0.574468 (-3928 4786);
PAINT GREEN (-3928 4786);
DISPLAY INVISIBLE (-3928 4786);
FORCEPROP 1 LAST VALUE BSS138K
J 0
(-3928 4921);
DISPLAY 0.574468 (-3928 4921);
PAINT GREEN (-3928 4921);
FORCEPROP 2 LAST PATH I177
J 0
(-3950 4975);
DISPLAY 1.021277 (-3950 4975);
FORCEPROP 1 LAST MATERIAL IC
J 0
(-3928 4731);
DISPLAY 0.574468 (-3928 4731);
PAINT GREEN (-3928 4731);
FORCEPROP 1 LAST $LOCATION U49
J 0
(-3928 4841);
DISPLAY 0.574468 (-3928 4841);
PAINT GREEN (-3928 4841);
FORCEPROP 1 LASTPIN (-4000 5000) $PN D
R 1
J 0
(-4000 4993);
DISPLAY 0.659574 (-4000 4993);
PAINT GREEN (-4000 4993);
FORCEPROP 1 LASTPIN (-4150 4800) $PN G
J 2
(-4140 4803);
DISPLAY 0.659574 (-4140 4803);
PAINT GREEN (-4140 4803);
FORCEPROP 1 LASTPIN (-4000 4700) $PN S
R 1
J 2
(-4000 4713);
DISPLAY 0.659574 (-4000 4713);
PAINT GREEN (-4000 4713);
FORCEPROP 0 LAST MANUF_PN BSS138K
J 0
(-3925 5025);
DISPLAY 0.510638 (-3925 5025);
DISPLAY INVISIBLE (-3925 5025);
FORCEPROP 1 LAST CDS_LMAN_SYM_OUTLINE -50,50,100,-150
J 0
(-4050 4900);
DISPLAY 0.468085 (-4050 4900);
PAINT GREEN (-4050 4900);
DISPLAY INVISIBLE (-4050 4900);
FORCEPROP 2 LAST CDS_LIB pure_quanta
J 0
(-4050 4900);
PAINT MONO (-4050 4900);
DISPLAY INVISIBLE (-4050 4900);
FORCEPROP 1 LAST PACK_TYPE SMLF
J 0
(-4025 4650);
DISPLAY 0.723404 (-4025 4650);
PAINT GREEN (-4025 4650);
DISPLAY INVISIBLE (-4025 4650);
FORCEPROP 2 LAST CDS_LOCATION U49
J 0
(-3925 5050);
DISPLAY 1.021277 (-3925 5050);
DISPLAY INVISIBLE (-3925 5050);
FORCEPROP 2 LAST $SEC 1
J 0
(-3925 5050);
DISPLAY 0.680851 (-3925 5050);
PAINT MONO (-3925 5050);
DISPLAY INVISIBLE (-3925 5050);
FORCEPROP 2 LAST CDS_SEC 1
J 0
(-3925 5050);
DISPLAY 1.021277 (-3925 5050);
DISPLAY INVISIBLE (-3925 5050);
FORCEADD OFFPAGE..1
(-3950 8200);
FORCEPROP 2 LAST $XR0 158 
J 0
(-4232 8200);
DISPLAY 0.638298 (-4232 8200);
PAINT MONO (-4232 8200);
FORCEPROP 1 LAST OFFPAGE TRUE
J 0
(-3625 8075);
DISPLAY 0.872340 (-3625 8075);
PAINT GREEN (-3625 8075);
DISPLAY INVISIBLE (-3625 8075);
FORCEPROP 1 LAST COMMENT_BODY TRUE
J 0
(-3825 8100);
DISPLAY 0.872340 (-3825 8100);
PAINT GREEN (-3825 8100);
DISPLAY INVISIBLE (-3825 8100);
FORCEPROP 2 LAST PATH I178
J 0
(-4250 8250);
DISPLAY 1.021277 (-4250 8250);
DISPLAY INVISIBLE (-4250 8250);
FORCEPROP 2 LAST CDS_LIB standard
J 0
(-3950 8200);
DISPLAY INVISIBLE (-3950 8200);
FORCEADD OFFPAGE..1
(-4975 4800);
FORCEPROP 2 LAST $XR1 158 
J 0
(-5377 4800);
DISPLAY 0.638298 (-5377 4800);
PAINT MONO (-5377 4800);
FORCEPROP 2 LAST $XR0 156 
J 0
(-5257 4800);
DISPLAY 0.638298 (-5257 4800);
PAINT MONO (-5257 4800);
FORCEPROP 2 LAST CDS_LIB standard
J 0
(-4975 4800);
PAINT MONO (-4975 4800);
DISPLAY INVISIBLE (-4975 4800);
FORCEPROP 1 LAST COMMENT_BODY TRUE
J 0
(-4850 4700);
DISPLAY 0.872340 (-4850 4700);
PAINT GREEN (-4850 4700);
DISPLAY INVISIBLE (-4850 4700);
FORCEPROP 1 LAST OFFPAGE TRUE
J 0
(-4650 4675);
DISPLAY 0.872340 (-4650 4675);
PAINT GREEN (-4650 4675);
DISPLAY INVISIBLE (-4650 4675);
FORCEPROP 2 LAST PATH I179
J 0
(-5250 4850);
DISPLAY 1.021277 (-5250 4850);
DISPLAY INVISIBLE (-5250 4850);
FORCEADD 74LVC1G08W57..1
(2400 6975);
FORCEPROP 1 LAST PART_NUMBER AL1G0008020
J 0
(2250 7181);
DISPLAY 0.723404 (2250 7181);
PAINT GREEN (2250 7181);
DISPLAY INVISIBLE (2250 7181);
FORCEPROP 1 LAST MATERIAL IC
J 0
(2256 7132);
DISPLAY 0.723404 (2256 7132);
PAINT GREEN (2256 7132);
FORCEPROP 2 LAST VALUE 74LVC1G08W5-7
J 0
(2250 7225);
DISPLAY 1.021277 (2250 7225);
FORCEPROP 2 LAST PART_TYPE SMLF
J 0
(2250 7350);
DISPLAY 1.021277 (2250 7350);
FORCEPROP 1 LAST $LOCATION U210
J 0
(2250 7306);
DISPLAY 0.723404 (2250 7306);
PAINT GREEN (2250 7306);
FORCEPROP 2 LASTPIN (2100 7075) $PN 1
J 2
(2090 7085);
DISPLAY 0.680851 (2090 7085);
PAINT MONO (2090 7085);
FORCEPROP 2 LASTPIN (2100 6975) $PN 2
J 2
(2090 6985);
DISPLAY 0.680851 (2090 6985);
PAINT MONO (2090 6985);
FORCEPROP 2 LASTPIN (2100 6875) $PN 3
J 2
(2090 6885);
DISPLAY 0.680851 (2090 6885);
PAINT MONO (2090 6885);
FORCEPROP 2 LASTPIN (2700 7075) $PN 5
J 0
(2710 7085);
DISPLAY 0.680851 (2710 7085);
PAINT MONO (2710 7085);
FORCEPROP 2 LASTPIN (2700 6925) $PN 4
J 0
(2710 6935);
DISPLAY 0.680851 (2710 6935);
PAINT MONO (2710 6935);
FORCEPROP 2 LAST CDS_LIB pure_quanta
J 0
(2400 6975);
DISPLAY INVISIBLE (2400 6975);
FORCEPROP 1 LAST PATH I189
J 0
(2400 6975);
DISPLAY 0.723404 (2400 6975);
PAINT GREEN (2400 6975);
DISPLAY INVISIBLE (2400 6975);
FORCEPROP 1 LAST NEEDS_NO_SIZE TRUE
J 0
(2400 6975);
DISPLAY 0.723404 (2400 6975);
PAINT GREEN (2400 6975);
DISPLAY INVISIBLE (2400 6975);
FORCEPROP 1 LAST CDS_LMAN_SYM_OUTLINE -150,150,150,-150
J 0
(2400 6975);
DISPLAY 0.468085 (2400 6975);
PAINT GREEN (2400 6975);
DISPLAY INVISIBLE (2400 6975);
FORCEPROP 0 LAST CDS_LOCATION U210
J 0
(2025 7500);
DISPLAY 1.021277 (2025 7500);
DISPLAY INVISIBLE (2025 7500);
FORCEPROP 2 LAST $SEC 1
J 0
(2025 7500);
DISPLAY 0.680851 (2025 7500);
PAINT MONO (2025 7500);
DISPLAY INVISIBLE (2025 7500);
FORCEPROP 2 LAST CDS_SEC 1
J 0
(2025 7500);
DISPLAY 1.021277 (2025 7500);
DISPLAY INVISIBLE (2025 7500);
FORCEADD 74LVC1G08W57..1
(-2925 5125);
FORCEPROP 1 LAST PART_NUMBER AL1G0008020
J 0
(-3069 5409);
DISPLAY 0.723404 (-3069 5409);
PAINT GREEN (-3069 5409);
DISPLAY INVISIBLE (-3069 5409);
FORCEPROP 2 LAST VALUE 74LVC1G08W5-7
J 0
(-3300 5475);
DISPLAY 1.021277 (-3300 5475);
FORCEPROP 2 LAST PART_TYPE SMLF
J 0
(-3275 5525);
DISPLAY 1.021277 (-3275 5525);
FORCEPROP 1 LAST MATERIAL IC
J 0
(-3069 5282);
DISPLAY 0.723404 (-3069 5282);
PAINT GREEN (-3069 5282);
FORCEPROP 1 LAST $LOCATION U208
J 0
(-3075 5350);
DISPLAY 0.723404 (-3075 5350);
PAINT GREEN (-3075 5350);
FORCEPROP 2 LASTPIN (-3225 5225) $PN 1
J 2
(-3235 5235);
DISPLAY 0.680851 (-3235 5235);
PAINT MONO (-3235 5235);
FORCEPROP 2 LASTPIN (-3225 5125) $PN 2
J 2
(-3235 5135);
DISPLAY 0.680851 (-3235 5135);
PAINT MONO (-3235 5135);
FORCEPROP 2 LASTPIN (-3225 5025) $PN 3
J 2
(-3235 5035);
DISPLAY 0.680851 (-3235 5035);
PAINT MONO (-3235 5035);
FORCEPROP 2 LASTPIN (-2625 5225) $PN 5
J 0
(-2615 5235);
DISPLAY 0.680851 (-2615 5235);
PAINT MONO (-2615 5235);
FORCEPROP 2 LASTPIN (-2625 5075) $PN 4
J 0
(-2615 5085);
DISPLAY 0.680851 (-2615 5085);
PAINT MONO (-2615 5085);
FORCEPROP 1 LAST NEEDS_NO_SIZE TRUE
J 0
(-2925 5125);
DISPLAY 0.723404 (-2925 5125);
PAINT GREEN (-2925 5125);
DISPLAY INVISIBLE (-2925 5125);
FORCEPROP 1 LAST CDS_LMAN_SYM_OUTLINE -150,150,150,-150
J 0
(-2925 5125);
DISPLAY 0.468085 (-2925 5125);
PAINT GREEN (-2925 5125);
DISPLAY INVISIBLE (-2925 5125);
FORCEPROP 1 LAST PATH I190
J 0
(-2925 5125);
DISPLAY 0.723404 (-2925 5125);
PAINT GREEN (-2925 5125);
DISPLAY INVISIBLE (-2925 5125);
FORCEPROP 2 LAST CDS_LIB pure_quanta
J 0
(-2925 5125);
DISPLAY INVISIBLE (-2925 5125);
FORCEPROP 0 LAST CDS_LOCATION U208
J 0
(-3275 5575);
DISPLAY 1.021277 (-3275 5575);
DISPLAY INVISIBLE (-3275 5575);
FORCEPROP 2 LAST $SEC 1
J 0
(-3050 5700);
DISPLAY 0.680851 (-3050 5700);
PAINT MONO (-3050 5700);
DISPLAY INVISIBLE (-3050 5700);
FORCEPROP 2 LAST CDS_SEC 1
J 0
(-3050 5700);
DISPLAY 1.021277 (-3050 5700);
DISPLAY INVISIBLE (-3050 5700);
FORCEADD Q_CAP..1
(-2475 9900);
FORCEPROP 1 LAST PART_NUMBER CH4104K1B00
J 0
(-2425 9750);
DISPLAY 0.510638 (-2425 9750);
DISPLAY INVISIBLE (-2425 9750);
FORCEPROP 1 LAST MATERIAL X7R
J 0
(-2425 9800);
DISPLAY 0.510638 (-2425 9800);
FORCEPROP 1 LAST TOLERANCE 10%
J 0
(-2425 9850);
DISPLAY 0.510638 (-2425 9850);
FORCEPROP 1 LAST VOLTAGE 25V
J 0
(-2425 9900);
DISPLAY 0.510638 (-2425 9900);
FORCEPROP 1 LAST PACK_TYPE 0402
J 0
(-2425 9700);
DISPLAY 0.510638 (-2425 9700);
FORCEPROP 1 LAST VALUE 0.1UF
J 0
(-2425 9950);
DISPLAY 0.510638 (-2425 9950);
FORCEPROP 1 LAST $LOCATION C579
J 0
(-2425 10000);
DISPLAY 0.978723 (-2425 10000);
FORCEPROP 1 LASTPIN (-2475 10000) $PN 1
J 0
(-2465 9980);
DISPLAY 0.787234 (-2465 9980);
FORCEPROP 1 LASTPIN (-2475 9800) $PN 2
J 0
(-2465 9780);
DISPLAY 0.787234 (-2465 9780);
FORCEPROP 2 LAST CDS_LIB pure_quanta
J 0
(-2475 9900);
PAINT MONO (-2475 9900);
DISPLAY INVISIBLE (-2475 9900);
FORCEPROP 1 LAST PATH I192
J 0
(-2425 10050);
DISPLAY 0.978723 (-2425 10050);
PAINT WHITE (-2425 10050);
DISPLAY INVISIBLE (-2425 10050);
FORCEPROP 2 LAST CDS_LOCATION C579
J 2
(-2425 10100);
DISPLAY 1.021277 (-2425 10100);
DISPLAY INVISIBLE (-2425 10100);
FORCEPROP 2 LAST $SEC 1
J 2
(-2425 10100);
DISPLAY 0.680851 (-2425 10100);
PAINT MONO (-2425 10100);
DISPLAY INVISIBLE (-2425 10100);
FORCEPROP 2 LAST CDS_SEC 1
J 2
(-2425 10100);
DISPLAY 1.021277 (-2425 10100);
DISPLAY INVISIBLE (-2425 10100);
FORCEADD UNIVERSAL_GND..1
(-2475 9675);
FORCEPROP 3 LASTPIN (-2475 9725) SIG_NAME GND\g
J 0
(-2465 9735);
DISPLAY 0.659574 (-2465 9735);
PAINT MONO (-2465 9735);
DISPLAY INVISIBLE (-2465 9735);
FORCEPROP 1 LAST HDL_POWER GND
J 1
(-2450 9600);
DISPLAY 0.872340 (-2450 9600);
PAINT GREEN (-2450 9600);
DISPLAY INVISIBLE (-2450 9600);
FORCEPROP 2 LAST CDS_LIB logical_power
J 0
(-2475 9675);
PAINT MONO (-2475 9675);
DISPLAY INVISIBLE (-2475 9675);
FORCEPROP 1 LAST PATH I193
J 0
(-2400 9675);
DISPLAY 0.872340 (-2400 9675);
PAINT AQUA (-2400 9675);
DISPLAY INVISIBLE (-2400 9675);
FORCEADD UNIVERSAL_POWER..1
(-2475 10175);
FORCEPROP 3 LASTPIN (-2475 10125) SIG_NAME P3V3_AUX\g
J 0
(-2465 10135);
DISPLAY 0.659574 (-2465 10135);
PAINT MONO (-2465 10135);
DISPLAY INVISIBLE (-2465 10135);
FORCEPROP 1 LAST HDL_POWER P3V3_AUX
J 1
(-2475 10225);
DISPLAY 0.872340 (-2475 10225);
PAINT GREEN (-2475 10225);
FORCEPROP 2 LAST CDS_LIB logical_power
J 0
(-2475 10175);
PAINT MONO (-2475 10175);
DISPLAY INVISIBLE (-2475 10175);
FORCEPROP 1 LAST PATH I194
J 0
(-2425 10200);
DISPLAY 0.872340 (-2425 10200);
PAINT AQUA (-2425 10200);
DISPLAY INVISIBLE (-2425 10200);
FORCEADD OFFPAGE..2
R 2
(-2850 9450);
FORCEPROP 2 LAST $XR0 158 
J 0
(-3135 9450);
DISPLAY 0.638298 (-3135 9450);
PAINT MONO (-3135 9450);
FORCEPROP 1 LAST COMMENT_BODY TRUE
J 2
(-2805 9355);
DISPLAY 0.872340 (-2805 9355);
PAINT GREEN (-2805 9355);
DISPLAY INVISIBLE (-2805 9355);
FORCEPROP 1 LAST OFFPAGE TRUE
J 2
(-3175 9325);
DISPLAY 0.872340 (-3175 9325);
PAINT GREEN (-3175 9325);
DISPLAY INVISIBLE (-3175 9325);
FORCEPROP 2 LAST CDS_LIB standard
J 2
(-2850 9450);
DISPLAY INVISIBLE (-2850 9450);
FORCEPROP 2 LAST PATH I201
J 2
(-3050 9500);
DISPLAY 1.021277 (-3050 9500);
DISPLAY INVISIBLE (-3050 9500);
FORCEADD OFFPAGE..1
R 2
(0 9450);
FORCEPROP 2 LAST $XR0 156 
J 0
(186 9450);
DISPLAY 0.638298 (186 9450);
PAINT MONO (186 9450);
FORCEPROP 2 LAST PATH I202
J 0
(300 9500);
DISPLAY 1.021277 (300 9500);
DISPLAY INVISIBLE (300 9500);
FORCEPROP 2 LAST CDS_LIB standard
J 2
(0 9450);
PAINT MONO (0 9450);
DISPLAY INVISIBLE (0 9450);
FORCEPROP 1 LAST OFFPAGE TRUE
J 2
(-325 9325);
DISPLAY 0.872340 (-325 9325);
PAINT GREEN (-325 9325);
DISPLAY INVISIBLE (-325 9325);
FORCEPROP 1 LAST COMMENT_BODY TRUE
J 2
(-125 9350);
DISPLAY 0.872340 (-125 9350);
PAINT GREEN (-125 9350);
DISPLAY INVISIBLE (-125 9350);
FORCEADD OFFPAGE..1
R 2
(0 9400);
FORCEPROP 2 LAST $XR1 158 
J 0
(306 9400);
DISPLAY 0.638298 (306 9400);
PAINT MONO (306 9400);
FORCEPROP 2 LAST $XR0 156 
J 0
(186 9400);
DISPLAY 0.638298 (186 9400);
PAINT MONO (186 9400);
FORCEPROP 2 LAST PATH I203
J 0
(325 9450);
DISPLAY 1.021277 (325 9450);
DISPLAY INVISIBLE (325 9450);
FORCEPROP 1 LAST OFFPAGE TRUE
J 2
(-325 9275);
DISPLAY 1.170213 (-325 9275);
PAINT GREEN (-325 9275);
DISPLAY INVISIBLE (-325 9275);
FORCEPROP 1 LAST COMMENT_BODY TRUE
J 2
(-125 9300);
DISPLAY 1.170213 (-125 9300);
PAINT GREEN (-125 9300);
DISPLAY INVISIBLE (-125 9300);
FORCEPROP 2 LAST CDS_LIB standard
J 0
(0 9400);
PAINT MONO (0 9400);
DISPLAY INVISIBLE (0 9400);
FORCEADD OFFPAGE..2
(0 9500);
FORCEPROP 2 LAST $XR0 158 
J 0
(189 9500);
DISPLAY 0.638298 (189 9500);
PAINT MONO (189 9500);
FORCEPROP 2 LAST CDS_LIB standard
J 0
(0 9500);
DISPLAY INVISIBLE (0 9500);
FORCEPROP 2 LAST PATH I205
J 0
(175 9575);
DISPLAY 1.021277 (175 9575);
DISPLAY INVISIBLE (175 9575);
FORCEPROP 1 LAST OFFPAGE TRUE
J 0
(325 9375);
DISPLAY 0.872340 (325 9375);
PAINT GREEN (325 9375);
DISPLAY INVISIBLE (325 9375);
FORCEPROP 1 LAST COMMENT_BODY TRUE
J 0
(-45 9405);
DISPLAY 0.872340 (-45 9405);
PAINT GREEN (-45 9405);
DISPLAY INVISIBLE (-45 9405);
FORCEADD PCA9555APW..1
(-1425 9250);
FORCEPROP 1 LAST PART_NUMBER AL009555K07
J 0
(-1648 9890);
DISPLAY 0.723404 (-1648 9890);
PAINT GREEN (-1648 9890);
DISPLAY INVISIBLE (-1648 9890);
FORCEPROP 1 LAST MATERIAL IC
J 0
(-1648 9763);
DISPLAY 0.723404 (-1648 9763);
PAINT GREEN (-1648 9763);
FORCEPROP 2 LAST PART_TYPE SMLF
J 0
(-1625 10125);
DISPLAY 1.021277 (-1625 10125);
FORCEPROP 2 LAST VALUE PCA9555APW
J 0
(-1625 10075);
DISPLAY 1.021277 (-1625 10075);
FORCEPROP 1 LAST LOCATION U209
J 0
(-1648 10037);
DISPLAY 0.723404 (-1648 10037);
PAINT GREEN (-1648 10037);
FORCEPROP 2 LASTPIN (-1800 9350) $PN 21
J 2
(-1810 9360);
DISPLAY 0.680851 (-1810 9360);
PAINT MONO (-1810 9360);
FORCEPROP 2 LASTPIN (-1800 9300) $PN 2
J 2
(-1810 9310);
DISPLAY 0.680851 (-1810 9310);
PAINT MONO (-1810 9310);
FORCEPROP 2 LASTPIN (-1800 9250) $PN 3
J 2
(-1810 9260);
DISPLAY 0.680851 (-1810 9260);
PAINT MONO (-1810 9260);
FORCEPROP 2 LASTPIN (-1800 9450) $PN 1
J 2
(-1810 9460);
DISPLAY 0.680851 (-1810 9460);
PAINT MONO (-1810 9460);
FORCEPROP 2 LASTPIN (-1050 9600) $PN 4
J 0
(-1040 9610);
DISPLAY 0.680851 (-1040 9610);
PAINT MONO (-1040 9610);
FORCEPROP 2 LASTPIN (-1050 9550) $PN 5
J 0
(-1040 9560);
DISPLAY 0.680851 (-1040 9560);
PAINT MONO (-1040 9560);
FORCEPROP 2 LASTPIN (-1050 9500) $PN 6
J 0
(-1040 9510);
DISPLAY 0.680851 (-1040 9510);
PAINT MONO (-1040 9510);
FORCEPROP 2 LASTPIN (-1050 9450) $PN 7
J 0
(-1040 9460);
DISPLAY 0.680851 (-1040 9460);
PAINT MONO (-1040 9460);
FORCEPROP 2 LASTPIN (-1050 9400) $PN 8
J 0
(-1040 9410);
DISPLAY 0.680851 (-1040 9410);
PAINT MONO (-1040 9410);
FORCEPROP 2 LASTPIN (-1050 9350) $PN 9
J 0
(-1040 9360);
DISPLAY 0.680851 (-1040 9360);
PAINT MONO (-1040 9360);
FORCEPROP 2 LASTPIN (-1050 9300) $PN 10
J 0
(-1040 9310);
DISPLAY 0.680851 (-1040 9310);
PAINT MONO (-1040 9310);
FORCEPROP 2 LASTPIN (-1050 9250) $PN 11
J 0
(-1040 9260);
DISPLAY 0.680851 (-1040 9260);
PAINT MONO (-1040 9260);
FORCEPROP 2 LASTPIN (-1050 9200) $PN 13
J 0
(-1040 9210);
DISPLAY 0.680851 (-1040 9210);
PAINT MONO (-1040 9210);
FORCEPROP 2 LASTPIN (-1050 9150) $PN 14
J 0
(-1040 9160);
DISPLAY 0.680851 (-1040 9160);
PAINT MONO (-1040 9160);
FORCEPROP 2 LASTPIN (-1050 9100) $PN 15
J 0
(-1040 9110);
DISPLAY 0.680851 (-1040 9110);
PAINT MONO (-1040 9110);
FORCEPROP 2 LASTPIN (-1050 9050) $PN 16
J 0
(-1040 9060);
DISPLAY 0.680851 (-1040 9060);
PAINT MONO (-1040 9060);
FORCEPROP 2 LASTPIN (-1050 9000) $PN 17
J 0
(-1040 9010);
DISPLAY 0.680851 (-1040 9010);
PAINT MONO (-1040 9010);
FORCEPROP 2 LASTPIN (-1050 8950) $PN 18
J 0
(-1040 8960);
DISPLAY 0.680851 (-1040 8960);
PAINT MONO (-1040 8960);
FORCEPROP 2 LASTPIN (-1050 8900) $PN 19
J 0
(-1040 8910);
DISPLAY 0.680851 (-1040 8910);
PAINT MONO (-1040 8910);
FORCEPROP 2 LASTPIN (-1050 8850) $PN 20
J 0
(-1040 8860);
DISPLAY 0.680851 (-1040 8860);
PAINT MONO (-1040 8860);
FORCEPROP 2 LASTPIN (-1800 9000) $PN 22
J 2
(-1810 9010);
DISPLAY 0.680851 (-1810 9010);
PAINT MONO (-1810 9010);
FORCEPROP 2 LASTPIN (-1800 9100) $PN 23
J 2
(-1810 9110);
DISPLAY 0.680851 (-1810 9110);
PAINT MONO (-1810 9110);
FORCEPROP 2 LASTPIN (-1800 9650) $PN 24
J 2
(-1810 9660);
DISPLAY 0.680851 (-1810 9660);
PAINT MONO (-1810 9660);
FORCEPROP 2 LASTPIN (-1800 8850) $PN 12
J 2
(-1810 8860);
DISPLAY 0.680851 (-1810 8860);
PAINT MONO (-1810 8860);
FORCEPROP 1 LAST NEEDS_NO_SIZE TRUE
J 0
(-1425 9250);
DISPLAY 0.723404 (-1425 9250);
PAINT GREEN (-1425 9250);
DISPLAY INVISIBLE (-1425 9250);
FORCEPROP 1 LAST PATH I206
J 0
(-1425 9250);
DISPLAY 0.723404 (-1425 9250);
PAINT GREEN (-1425 9250);
DISPLAY INVISIBLE (-1425 9250);
FORCEPROP 2 LAST SEC_TYPE 
J 0
(-1625 10175);
DISPLAY 1.021277 (-1625 10175);
DISPLAY INVISIBLE (-1625 10175);
FORCEPROP 1 LAST CDS_LMAN_SYM_OUTLINE -225,500,225,-500
J 0
(-1425 9250);
DISPLAY 0.468085 (-1425 9250);
PAINT GREEN (-1425 9250);
DISPLAY INVISIBLE (-1425 9250);
FORCEPROP 2 LAST CDS_LIB pure_quanta
J 0
(-1425 9250);
DISPLAY INVISIBLE (-1425 9250);
FORCEPROP 2 LAST SEC 1
J 0
(-1625 10175);
DISPLAY 0.680851 (-1625 10175);
PAINT MONO (-1625 10175);
DISPLAY INVISIBLE (-1625 10175);
FORCEADD OFFPAGE..6
(-2850 9100);
FORCEPROP 2 LAST $XR0 158 
J 0
(-3160 9100);
DISPLAY 0.638298 (-3160 9100);
PAINT MONO (-3160 9100);
FORCEPROP 2 LAST PATH I207
J 0
(-3150 9150);
DISPLAY 1.021277 (-3150 9150);
DISPLAY INVISIBLE (-3150 9150);
FORCEPROP 1 LAST COMMENT_BODY TRUE
J 0
(-2750 9025);
DISPLAY 0.872340 (-2750 9025);
PAINT GREEN (-2750 9025);
DISPLAY INVISIBLE (-2750 9025);
FORCEPROP 1 LAST OFFPAGE TRUE
J 0
(-2525 8975);
DISPLAY 0.872340 (-2525 8975);
DISPLAY INVISIBLE (-2525 8975);
FORCEPROP 2 LAST CDS_LIB standard
J 2
(-2850 9100);
DISPLAY INVISIBLE (-2850 9100);
FORCEADD OFFPAGE..1
(-2850 9000);
FORCEPROP 2 LAST $XR0 158 
J 0
(-3102 9000);
DISPLAY 0.638298 (-3102 9000);
PAINT MONO (-3102 9000);
FORCEPROP 2 LAST PATH I208
J 0
(-3100 9050);
DISPLAY 1.021277 (-3100 9050);
DISPLAY INVISIBLE (-3100 9050);
FORCEPROP 1 LAST OFFPAGE TRUE
J 0
(-2525 8875);
DISPLAY 1.170213 (-2525 8875);
PAINT GREEN (-2525 8875);
DISPLAY INVISIBLE (-2525 8875);
FORCEPROP 1 LAST COMMENT_BODY TRUE
J 0
(-2725 8900);
DISPLAY 1.170213 (-2725 8900);
PAINT GREEN (-2725 8900);
DISPLAY INVISIBLE (-2725 8900);
FORCEPROP 2 LAST CDS_LIB standard
J 2
(-2850 9000);
PAINT MONO (-2850 9000);
DISPLAY INVISIBLE (-2850 9000);
FORCEADD 74LVC1G08W57..1
(-125 7125);
FORCEPROP 1 LAST PART_NUMBER AL1G0008020
J 0
(-269 7409);
DISPLAY 0.723404 (-269 7409);
PAINT GREEN (-269 7409);
DISPLAY INVISIBLE (-269 7409);
FORCEPROP 1 LAST MATERIAL IC
J 0
(-269 7282);
DISPLAY 0.723404 (-269 7282);
PAINT GREEN (-269 7282);
FORCEPROP 2 LAST PART_TYPE SMLF
J 0
(-500 7600);
DISPLAY 1.021277 (-500 7600);
FORCEPROP 2 LAST VALUE 74LVC1G08W5-7
J 0
(-525 7475);
DISPLAY 1.021277 (-525 7475);
FORCEPROP 1 LAST $LOCATION U322
J 0
(-269 7556);
DISPLAY 0.723404 (-269 7556);
PAINT GREEN (-269 7556);
FORCEPROP 2 LASTPIN (-425 7225) $PN 1
J 2
(-435 7235);
DISPLAY 0.680851 (-435 7235);
PAINT MONO (-435 7235);
FORCEPROP 2 LASTPIN (-425 7125) $PN 2
J 2
(-435 7135);
DISPLAY 0.680851 (-435 7135);
PAINT MONO (-435 7135);
FORCEPROP 2 LASTPIN (-425 7025) $PN 3
J 2
(-435 7035);
DISPLAY 0.680851 (-435 7035);
PAINT MONO (-435 7035);
FORCEPROP 2 LASTPIN (175 7225) $PN 5
J 0
(185 7235);
DISPLAY 0.680851 (185 7235);
PAINT MONO (185 7235);
FORCEPROP 2 LASTPIN (175 7075) $PN 4
J 0
(185 7085);
DISPLAY 0.680851 (185 7085);
PAINT MONO (185 7085);
FORCEPROP 1 LAST PATH I221
J 0
(-125 7125);
DISPLAY 0.723404 (-125 7125);
PAINT GREEN (-125 7125);
DISPLAY INVISIBLE (-125 7125);
FORCEPROP 1 LAST CDS_LMAN_SYM_OUTLINE -150,150,150,-150
J 0
(-125 7125);
DISPLAY 0.468085 (-125 7125);
PAINT GREEN (-125 7125);
DISPLAY INVISIBLE (-125 7125);
FORCEPROP 1 LAST NEEDS_NO_SIZE TRUE
J 0
(-125 7125);
DISPLAY 0.723404 (-125 7125);
PAINT GREEN (-125 7125);
DISPLAY INVISIBLE (-125 7125);
FORCEPROP 2 LAST CDS_LIB pure_quanta
J 0
(-125 7125);
DISPLAY INVISIBLE (-125 7125);
FORCEPROP 0 LAST CDS_LOCATION U322
J 0
(-500 7650);
DISPLAY 1.021277 (-500 7650);
DISPLAY INVISIBLE (-500 7650);
FORCEPROP 2 LAST $SEC 1
J 0
(-500 7650);
DISPLAY 0.680851 (-500 7650);
PAINT MONO (-500 7650);
DISPLAY INVISIBLE (-500 7650);
FORCEPROP 2 LAST CDS_SEC 1
J 0
(-500 7650);
DISPLAY 1.021277 (-500 7650);
DISPLAY INVISIBLE (-500 7650);
FORCEADD UNIVERSAL_POWER..1
(425 7900);
FORCEPROP 3 LASTPIN (425 7850) SIG_NAME P3V3_AUX\g
J 0
(435 7860);
DISPLAY 0.659574 (435 7860);
PAINT MONO (435 7860);
DISPLAY INVISIBLE (435 7860);
FORCEPROP 1 LAST HDL_POWER P3V3_AUX
J 1
(425 7950);
DISPLAY 0.872340 (425 7950);
PAINT GREEN (425 7950);
FORCEPROP 2 LAST CDS_LIB logical_power
J 0
(425 7900);
PAINT MONO (425 7900);
DISPLAY INVISIBLE (425 7900);
FORCEPROP 1 LAST PATH I222
J 0
(475 7925);
DISPLAY 0.872340 (475 7925);
PAINT AQUA (475 7925);
DISPLAY INVISIBLE (475 7925);
FORCEADD Q_CAP..1
(425 7625);
FORCEPROP 1 LAST PART_NUMBER CH4104K1B00
J 0
(475 7475);
DISPLAY 0.510638 (475 7475);
DISPLAY INVISIBLE (475 7475);
FORCEPROP 1 LAST VOLTAGE 25V
J 0
(475 7625);
DISPLAY 0.510638 (475 7625);
FORCEPROP 1 LAST PACK_TYPE 0402
J 0
(475 7425);
DISPLAY 0.510638 (475 7425);
FORCEPROP 1 LAST MATERIAL X7R
J 0
(475 7525);
DISPLAY 0.510638 (475 7525);
FORCEPROP 1 LAST TOLERANCE 10%
J 0
(475 7575);
DISPLAY 0.510638 (475 7575);
FORCEPROP 1 LAST VALUE 0.1UF
J 0
(475 7675);
DISPLAY 0.510638 (475 7675);
FORCEPROP 1 LAST $LOCATION C2346
J 0
(475 7725);
DISPLAY 0.978723 (475 7725);
FORCEPROP 1 LASTPIN (425 7725) $PN 1
J 0
(435 7705);
DISPLAY 0.787234 (435 7705);
FORCEPROP 1 LASTPIN (425 7525) $PN 2
J 0
(435 7505);
DISPLAY 0.787234 (435 7505);
FORCEPROP 1 LAST PATH I223
J 0
(475 7775);
DISPLAY 0.978723 (475 7775);
PAINT WHITE (475 7775);
DISPLAY INVISIBLE (475 7775);
FORCEPROP 2 LAST CDS_LIB pure_quanta
J 2
(425 7625);
PAINT MONO (425 7625);
DISPLAY INVISIBLE (425 7625);
FORCEPROP 2 LAST CDS_LOCATION C2346
J 0
(475 7825);
DISPLAY 1.021277 (475 7825);
DISPLAY INVISIBLE (475 7825);
FORCEPROP 2 LAST $SEC 1
J 0
(475 7825);
DISPLAY 0.680851 (475 7825);
PAINT MONO (475 7825);
DISPLAY INVISIBLE (475 7825);
FORCEPROP 2 LAST CDS_SEC 1
J 0
(475 7825);
DISPLAY 1.021277 (475 7825);
DISPLAY INVISIBLE (475 7825);
FORCEADD UNIVERSAL_GND..1
(425 7400);
FORCEPROP 3 LASTPIN (425 7450) SIG_NAME GND\g
J 0
(435 7460);
DISPLAY 0.659574 (435 7460);
PAINT MONO (435 7460);
DISPLAY INVISIBLE (435 7460);
FORCEPROP 1 LAST PATH I224
J 0
(500 7400);
DISPLAY 0.872340 (500 7400);
PAINT AQUA (500 7400);
DISPLAY INVISIBLE (500 7400);
FORCEPROP 1 LAST HDL_POWER GND
J 1
(450 7325);
DISPLAY 0.872340 (450 7325);
PAINT GREEN (450 7325);
DISPLAY INVISIBLE (450 7325);
FORCEPROP 2 LAST CDS_LIB logical_power
J 0
(425 7400);
PAINT MONO (425 7400);
DISPLAY INVISIBLE (425 7400);
FORCEADD UNIVERSAL_GND..1
(-475 6900);
FORCEPROP 3 LASTPIN (-475 6950) SIG_NAME GND\g
J 0
(-465 6960);
DISPLAY 0.659574 (-465 6960);
PAINT MONO (-465 6960);
DISPLAY INVISIBLE (-465 6960);
FORCEPROP 1 LAST PATH I225
J 0
(-400 6900);
DISPLAY 0.872340 (-400 6900);
PAINT AQUA (-400 6900);
DISPLAY INVISIBLE (-400 6900);
FORCEPROP 1 LAST HDL_POWER GND
J 1
(-450 6825);
DISPLAY 0.872340 (-450 6825);
PAINT GREEN (-450 6825);
DISPLAY INVISIBLE (-450 6825);
FORCEPROP 2 LAST CDS_LIB logical_power
J 0
(-475 6900);
PAINT MONO (-475 6900);
DISPLAY INVISIBLE (-475 6900);
FORCEADD UNIVERSAL_GND..1
(-2975 7300);
FORCEPROP 3 LASTPIN (-2975 7350) SIG_NAME GND\g
J 0
(-2965 7360);
DISPLAY 0.659574 (-2965 7360);
PAINT MONO (-2965 7360);
DISPLAY INVISIBLE (-2965 7360);
FORCEPROP 1 LAST HDL_POWER GND
J 1
(-2950 7225);
DISPLAY 0.872340 (-2950 7225);
PAINT GREEN (-2950 7225);
DISPLAY INVISIBLE (-2950 7225);
FORCEPROP 2 LAST CDS_LIB logical_power
J 0
(-2975 7300);
PAINT MONO (-2975 7300);
DISPLAY INVISIBLE (-2975 7300);
FORCEPROP 1 LAST PATH I226
J 0
(-2900 7300);
DISPLAY 0.872340 (-2900 7300);
PAINT AQUA (-2900 7300);
DISPLAY INVISIBLE (-2900 7300);
FORCEADD UNIVERSAL_POWER..1
(-4175 7475);
FORCEPROP 3 LASTPIN (-4175 7425) SIG_NAME P3V3_OCP_SFF\g
J 0
(-4165 7435);
DISPLAY 0.659574 (-4165 7435);
PAINT MONO (-4165 7435);
DISPLAY INVISIBLE (-4165 7435);
FORCEPROP 1 LAST HDL_POWER P3V3_OCP_SFF
J 1
(-4175 7525);
DISPLAY 0.872340 (-4175 7525);
PAINT GREEN (-4175 7525);
FORCEPROP 1 LAST PATH I227
J 0
(-4125 7500);
DISPLAY 0.872340 (-4125 7500);
PAINT AQUA (-4125 7500);
DISPLAY INVISIBLE (-4125 7500);
FORCEPROP 2 LAST CDS_LIB logical_power
J 0
(-4175 7475);
PAINT MONO (-4175 7475);
DISPLAY INVISIBLE (-4175 7475);
FORCEADD APX80929SAG7..1
R 2
(-3475 7325);
FORCEPROP 1 LAST PART_NUMBER AL080929000
J 2
(-3250 7592);
DISPLAY 0.723404 (-3250 7592);
PAINT GREEN (-3250 7592);
DISPLAY INVISIBLE (-3250 7592);
FORCEPROP 2 LAST PART_TYPE SMLF
J 2
(-3250 7750);
DISPLAY 1.021277 (-3250 7750);
FORCEPROP 2 LAST VALUE APX809-29SAG-7
J 2
(-3250 7700);
DISPLAY 1.021277 (-3250 7700);
FORCEPROP 1 LAST MATERIAL IC
J 2
(-3250 7535);
DISPLAY 0.723404 (-3250 7535);
PAINT GREEN (-3250 7535);
FORCEPROP 1 LAST LOCATION U52
J 2
(-3250 7644);
DISPLAY 0.723404 (-3250 7644);
PAINT GREEN (-3250 7644);
FORCEPROP 2 LASTPIN (-3100 7425) $PN 1
J 0
(-3090 7435);
DISPLAY 0.808511 (-3090 7435);
FORCEPROP 2 LASTPIN (-3100 7225) $PN 2
J 0
(-3090 7235);
DISPLAY 0.808511 (-3090 7235);
FORCEPROP 2 LASTPIN (-3850 7325) $PN 3
J 2
(-3860 7335);
DISPLAY 0.808511 (-3860 7335);
FORCEPROP 1 LAST CDS_LMAN_SYM_OUTLINE -225,200,225,-200
J 2
(-3475 7325);
DISPLAY 0.468085 (-3475 7325);
PAINT GREEN (-3475 7325);
DISPLAY INVISIBLE (-3475 7325);
FORCEPROP 1 LAST NEEDS_NO_SIZE TRUE
J 2
(-3700 7165);
DISPLAY 0.723404 (-3700 7165);
PAINT GREEN (-3700 7165);
DISPLAY INVISIBLE (-3700 7165);
FORCEPROP 2 LAST CDS_LIB pure_quanta
J 2
(-3475 7325);
PAINT MONO (-3475 7325);
DISPLAY INVISIBLE (-3475 7325);
FORCEPROP 1 LAST PATH I228
J 2
(-3700 7125);
DISPLAY 0.723404 (-3700 7125);
PAINT GREEN (-3700 7125);
DISPLAY INVISIBLE (-3700 7125);
FORCEPROP 2 LAST $SEC 1
J 0
(-3250 7800);
DISPLAY 0.680851 (-3250 7800);
PAINT MONO (-3250 7800);
DISPLAY INVISIBLE (-3250 7800);
FORCEPROP 2 LAST CDS_SEC 1
J 0
(-3250 7800);
DISPLAY 1.021277 (-3250 7800);
DISPLAY INVISIBLE (-3250 7800);
FORCEADD Q_CAP..1
R 2
(-4175 7150);
FORCEPROP 1 LAST PART_NUMBER CH4104K1B00
J 2
(-4225 7000);
DISPLAY 0.510638 (-4225 7000);
DISPLAY INVISIBLE (-4225 7000);
FORCEPROP 1 LAST VOLTAGE 25V
J 2
(-4225 7150);
DISPLAY 0.510638 (-4225 7150);
FORCEPROP 1 LAST VALUE 0.1UF
J 2
(-4225 7200);
DISPLAY 0.510638 (-4225 7200);
FORCEPROP 1 LAST MATERIAL X7R
J 2
(-4225 7050);
DISPLAY 0.510638 (-4225 7050);
FORCEPROP 1 LAST PACK_TYPE 0402
J 2
(-4225 6950);
DISPLAY 0.510638 (-4225 6950);
FORCEPROP 1 LAST TOLERANCE 10%
J 2
(-4225 7100);
DISPLAY 0.510638 (-4225 7100);
FORCEPROP 1 LAST LOCATION C580
J 2
(-4225 7250);
DISPLAY 0.978723 (-4225 7250);
FORCEPROP 1 LASTPIN (-4175 7250) $PN 1
J 2
(-4185 7230);
DISPLAY 0.787234 (-4185 7230);
FORCEPROP 1 LASTPIN (-4175 7050) $PN 2
J 2
(-4185 7030);
DISPLAY 0.787234 (-4185 7030);
FORCEPROP 2 LAST CDS_LIB pure_quanta
J 2
(-4175 7150);
PAINT MONO (-4175 7150);
DISPLAY INVISIBLE (-4175 7150);
FORCEPROP 1 LAST PATH I229
J 2
(-4225 7300);
DISPLAY 0.978723 (-4225 7300);
PAINT WHITE (-4225 7300);
DISPLAY INVISIBLE (-4225 7300);
FORCEPROP 2 LAST $SEC 1
J 0
(-4225 7350);
DISPLAY 0.680851 (-4225 7350);
PAINT MONO (-4225 7350);
DISPLAY INVISIBLE (-4225 7350);
FORCEPROP 2 LAST CDS_SEC 1
J 0
(-4225 7350);
DISPLAY 1.021277 (-4225 7350);
DISPLAY INVISIBLE (-4225 7350);
FORCEADD UNIVERSAL_GND..1
(-4175 6925);
FORCEPROP 3 LASTPIN (-4175 6975) SIG_NAME GND\g
J 0
(-4165 6985);
DISPLAY 0.659574 (-4165 6985);
PAINT MONO (-4165 6985);
DISPLAY INVISIBLE (-4165 6985);
FORCEPROP 1 LAST HDL_POWER GND
J 1
(-4150 6850);
DISPLAY 0.872340 (-4150 6850);
PAINT GREEN (-4150 6850);
DISPLAY INVISIBLE (-4150 6850);
FORCEPROP 2 LAST CDS_LIB logical_power
J 0
(-4175 6925);
PAINT MONO (-4175 6925);
DISPLAY INVISIBLE (-4175 6925);
FORCEPROP 1 LAST PATH I230
J 0
(-4100 6925);
DISPLAY 0.872340 (-4100 6925);
PAINT AQUA (-4100 6925);
DISPLAY INVISIBLE (-4100 6925);
FORCEADD Q_RES..1
(-1900 7550);
FORCEPROP 1 LAST PART_NUMBER CS00002JB13
J 0
(-2025 7625);
DISPLAY 0.638298 (-2025 7625);
DISPLAY INVISIBLE (-2025 7625);
FORCEPROP 1 LAST MATERIAL EMPTY
J 0
(-1750 7500);
DISPLAY 0.638298 (-1750 7500);
PAINT RED (-1750 7500);
FORCEPROP 1 LAST PACK_TYPE 0402LF
J 0
(-1625 7550);
DISPLAY 0.638298 (-1625 7550);
FORCEPROP 1 LAST VALUE 0
J 2
(-1725 7550);
DISPLAY 0.638298 (-1725 7550);
FORCEPROP 1 LAST TOLERANCE 5%
J 0
(-1700 7550);
DISPLAY 0.638298 (-1700 7550);
FORCEPROP 1 LAST $LOCATION R4613
J 0
(-2125 7550);
DISPLAY 0.638298 (-2125 7550);
FORCEPROP 1 LASTPIN (-2000 7550) $PN 1
J 0
(-1988 7562);
DISPLAY 0.787234 (-1988 7562);
PAINT MONO (-1988 7562);
FORCEPROP 1 LASTPIN (-1800 7550) $PN 2
J 0
(-1838 7562);
DISPLAY 0.787234 (-1838 7562);
PAINT MONO (-1838 7562);
FORCEPROP 2 LAST CDS_LIB pure_quanta
J 0
(-1900 7550);
DISPLAY INVISIBLE (-1900 7550);
FORCEPROP 1 LAST PATH I232
J 0
(-1950 7700);
DISPLAY 0.978723 (-1950 7700);
PAINT WHITE (-1950 7700);
DISPLAY INVISIBLE (-1950 7700);
FORCEPROP 1 LAST WATTAGE 1/16W
J 2
(-1725 7675);
DISPLAY 0.638298 (-1725 7675);
DISPLAY INVISIBLE (-1725 7675);
FORCEPROP 0 LAST CDS_LOCATION R4613
J 0
(-1950 7650);
DISPLAY 1.021277 (-1950 7650);
DISPLAY INVISIBLE (-1950 7650);
FORCEPROP 0 LAST $SEC 1
J 0
(-1950 7650);
DISPLAY 0.680851 (-1950 7650);
PAINT MONO (-1950 7650);
DISPLAY INVISIBLE (-1950 7650);
FORCEPROP 0 LAST CDS_SEC 1
J 0
(-1950 7650);
DISPLAY 1.021277 (-1950 7650);
DISPLAY INVISIBLE (-1950 7650);
FORCEADD OFFPAGE..1
(-2750 7550);
FORCEPROP 2 LAST $XR0 156 
J 0
(-3002 7550);
DISPLAY 0.638298 (-3002 7550);
PAINT MONO (-3002 7550);
FORCEPROP 1 LAST COMMENT_BODY TRUE
J 0
(-2625 7450);
DISPLAY 0.872340 (-2625 7450);
PAINT GREEN (-2625 7450);
DISPLAY INVISIBLE (-2625 7450);
FORCEPROP 1 LAST OFFPAGE TRUE
J 0
(-2425 7425);
DISPLAY 0.872340 (-2425 7425);
PAINT GREEN (-2425 7425);
DISPLAY INVISIBLE (-2425 7425);
FORCEPROP 2 LAST PATH I233
J 0
(-2700 7625);
DISPLAY 1.021277 (-2700 7625);
DISPLAY INVISIBLE (-2700 7625);
FORCEPROP 2 LAST CDS_LIB standard
J 0
(-2750 7550);
DISPLAY INVISIBLE (-2750 7550);
FORCEADD Q_RES..2
(-1325 7800);
FORCEPROP 1 LAST PART_NUMBER CS21002FB06
J 0
(-1285 7625);
DISPLAY 0.638298 (-1285 7625);
DISPLAY INVISIBLE (-1285 7625);
FORCEPROP 1 LAST WATTAGE 1/16W
J 0
(-1285 7775);
DISPLAY 0.638298 (-1285 7775);
FORCEPROP 1 LAST TOLERANCE 1%
J 0
(-1280 7825);
DISPLAY 0.638298 (-1280 7825);
FORCEPROP 1 LAST VALUE 1K
J 0
(-1280 7875);
DISPLAY 0.638298 (-1280 7875);
FORCEPROP 1 LAST MATERIAL EMPTY
J 0
(-1285 7725);
DISPLAY 0.638298 (-1285 7725);
PAINT RED (-1285 7725);
FORCEPROP 1 LAST PACK_TYPE 0402LF
J 0
(-1285 7675);
DISPLAY 0.638298 (-1285 7675);
FORCEPROP 1 LAST $LOCATION R3160
J 0
(-1280 7925);
DISPLAY 0.978723 (-1280 7925);
FORCEPROP 1 LASTPIN (-1325 7900) $PN 1
J 0
(-1320 7862);
DISPLAY 0.787234 (-1320 7862);
FORCEPROP 1 LASTPIN (-1325 7700) $PN 2
J 0
(-1320 7710);
DISPLAY 0.787234 (-1320 7710);
FORCEPROP 1 LAST PATH I235
J 0
(-1275 7975);
DISPLAY 0.978723 (-1275 7975);
PAINT WHITE (-1275 7975);
DISPLAY INVISIBLE (-1275 7975);
FORCEPROP 2 LAST CDS_LIB pure_quanta
J 0
(-1325 7800);
PAINT MONO (-1325 7800);
DISPLAY INVISIBLE (-1325 7800);
FORCEPROP 2 LAST CDS_LOCATION R3160
J 0
(-1275 8025);
DISPLAY 1.021277 (-1275 8025);
DISPLAY INVISIBLE (-1275 8025);
FORCEPROP 2 LAST $SEC 1
J 0
(-1275 8025);
DISPLAY 0.680851 (-1275 8025);
PAINT MONO (-1275 8025);
DISPLAY INVISIBLE (-1275 8025);
FORCEPROP 2 LAST CDS_SEC 1
J 0
(-1275 8025);
DISPLAY 1.021277 (-1275 8025);
DISPLAY INVISIBLE (-1275 8025);
FORCEADD UNIVERSAL_POWER..1
(-1325 8025);
FORCEPROP 3 LASTPIN (-1325 7975) SIG_NAME P3V3_AUX\g
J 0
(-1315 7985);
DISPLAY 0.659574 (-1315 7985);
PAINT MONO (-1315 7985);
DISPLAY INVISIBLE (-1315 7985);
FORCEPROP 1 LAST HDL_POWER P3V3_AUX
J 1
(-1325 8075);
DISPLAY 0.872340 (-1325 8075);
PAINT GREEN (-1325 8075);
FORCEPROP 2 LAST CDS_LIB logical_power
J 0
(-1325 8025);
DISPLAY INVISIBLE (-1325 8025);
FORCEPROP 1 LAST PATH I236
J 0
(-1275 8050);
DISPLAY 0.872340 (-1275 8050);
PAINT AQUA (-1275 8050);
DISPLAY INVISIBLE (-1275 8050);
FORCEADD Q_RES..1
(1075 7075);
FORCEPROP 1 LAST PART_NUMBER CS03322FB03
J 0
(950 7125);
DISPLAY 0.638298 (950 7125);
DISPLAY INVISIBLE (950 7125);
FORCEPROP 1 LAST MATERIAL CHIP
J 0
(850 7025);
DISPLAY 0.638298 (850 7025);
FORCEPROP 1 LAST PACK_TYPE 0402LF
J 0
(1375 7050);
DISPLAY 0.510638 (1375 7050);
FORCEPROP 1 LAST VALUE 33.2
J 2
(1250 7050);
DISPLAY 0.510638 (1250 7050);
FORCEPROP 1 LAST TOLERANCE 1%
J 0
(1275 7050);
DISPLAY 0.510638 (1275 7050);
FORCEPROP 1 LAST $LOCATION R4618
J 0
(850 7075);
DISPLAY 0.638298 (850 7075);
FORCEPROP 1 LASTPIN (975 7075) $PN 1
J 0
(987 7087);
DISPLAY 0.787234 (987 7087);
PAINT MONO (987 7087);
FORCEPROP 1 LASTPIN (1175 7075) $PN 2
J 0
(1137 7087);
DISPLAY 0.787234 (1137 7087);
PAINT MONO (1137 7087);
FORCEPROP 2 LAST CDS_LIB pure_quanta
J 0
(1075 7075);
DISPLAY INVISIBLE (1075 7075);
FORCEPROP 1 LAST PATH I237
J 0
(1025 7225);
DISPLAY 0.978723 (1025 7225);
PAINT WHITE (1025 7225);
DISPLAY INVISIBLE (1025 7225);
FORCEPROP 1 LAST WATTAGE 1/16W
J 2
(1275 7175);
DISPLAY 0.638298 (1275 7175);
DISPLAY INVISIBLE (1275 7175);
FORCEPROP 0 LAST CDS_LOCATION R4618
J 0
(950 7125);
DISPLAY 1.021277 (950 7125);
DISPLAY INVISIBLE (950 7125);
FORCEPROP 0 LAST $SEC 1
J 0
(950 7125);
DISPLAY 0.680851 (950 7125);
PAINT MONO (950 7125);
DISPLAY INVISIBLE (950 7125);
FORCEPROP 0 LAST CDS_SEC 1
J 0
(950 7125);
DISPLAY 1.021277 (950 7125);
DISPLAY INVISIBLE (950 7125);
FORCEADD Q_RES..1
(-1875 7225);
FORCEPROP 1 LAST PART_NUMBER CS03322FB03
J 0
(-2000 7275);
DISPLAY 0.638298 (-2000 7275);
DISPLAY INVISIBLE (-2000 7275);
FORCEPROP 1 LAST PACK_TYPE 0402LF
J 0
(-1575 7200);
DISPLAY 0.510638 (-1575 7200);
FORCEPROP 1 LAST TOLERANCE 1%
J 0
(-1675 7200);
DISPLAY 0.510638 (-1675 7200);
FORCEPROP 1 LAST VALUE 33.2
J 2
(-1700 7200);
DISPLAY 0.510638 (-1700 7200);
FORCEPROP 1 LAST MATERIAL CHIP
J 0
(-1800 7225);
DISPLAY 0.638298 (-1800 7225);
FORCEPROP 1 LAST LOCATION R4614
J 0
(-2125 7225);
DISPLAY 0.638298 (-2125 7225);
FORCEPROP 1 LASTPIN (-1975 7225) $PN 1
J 0
(-1963 7237);
DISPLAY 0.787234 (-1963 7237);
PAINT MONO (-1963 7237);
FORCEPROP 1 LASTPIN (-1775 7225) $PN 2
J 0
(-1813 7237);
DISPLAY 0.787234 (-1813 7237);
PAINT MONO (-1813 7237);
FORCEPROP 2 LAST CDS_LIB pure_quanta
J 0
(-1875 7225);
DISPLAY INVISIBLE (-1875 7225);
FORCEPROP 1 LAST PATH I238
J 0
(-1925 7375);
DISPLAY 0.978723 (-1925 7375);
PAINT WHITE (-1925 7375);
DISPLAY INVISIBLE (-1925 7375);
FORCEPROP 1 LAST WATTAGE 1/16W
J 2
(-1675 7325);
DISPLAY 0.638298 (-1675 7325);
DISPLAY INVISIBLE (-1675 7325);
FORCEPROP 0 LAST $SEC 1
J 0
(-1800 7275);
DISPLAY 0.680851 (-1800 7275);
PAINT MONO (-1800 7275);
DISPLAY INVISIBLE (-1800 7275);
FORCEPROP 0 LAST CDS_SEC 1
J 0
(-1800 7275);
DISPLAY 1.021277 (-1800 7275);
DISPLAY INVISIBLE (-1800 7275);
FORCEADD OFFPAGE..2
(1475 7450);
FORCEPROP 2 LAST $XR1 216 
J 0
(1784 7450);
DISPLAY 0.638298 (1784 7450);
PAINT MONO (1784 7450);
FORCEPROP 2 LAST $XR0 158 
J 0
(1664 7450);
DISPLAY 0.638298 (1664 7450);
PAINT MONO (1664 7450);
FORCEPROP 1 LAST OFFPAGE TRUE
J 0
(1800 7325);
DISPLAY 0.872340 (1800 7325);
PAINT GREEN (1800 7325);
DISPLAY INVISIBLE (1800 7325);
FORCEPROP 1 LAST COMMENT_BODY TRUE
J 0
(1430 7355);
DISPLAY 0.872340 (1430 7355);
PAINT GREEN (1430 7355);
DISPLAY INVISIBLE (1430 7355);
FORCEPROP 2 LAST PATH I239
J 0
(1650 7525);
DISPLAY 1.021277 (1650 7525);
DISPLAY INVISIBLE (1650 7525);
FORCEPROP 2 LAST CDS_LIB standard
J 0
(1475 7450);
DISPLAY INVISIBLE (1475 7450);
FORCEADD UNIVERSAL_POWER..1
(1475 6275);
FORCEPROP 3 LASTPIN (1475 6225) SIG_NAME P3V3_AUX\g
J 0
(1485 6235);
DISPLAY 0.659574 (1485 6235);
PAINT MONO (1485 6235);
DISPLAY INVISIBLE (1485 6235);
FORCEPROP 1 LAST HDL_POWER P3V3_AUX
J 1
(1475 6325);
DISPLAY 0.872340 (1475 6325);
PAINT GREEN (1475 6325);
FORCEPROP 2 LAST CDS_LIB logical_power
J 0
(1475 6275);
PAINT MONO (1475 6275);
DISPLAY INVISIBLE (1475 6275);
FORCEPROP 1 LAST PATH I240
J 0
(1525 6300);
DISPLAY 0.872340 (1525 6300);
PAINT AQUA (1525 6300);
DISPLAY INVISIBLE (1525 6300);
FORCEADD Q_CAP..1
(1475 6000);
FORCEPROP 1 LAST PART_NUMBER CH4104K1B00
J 0
(1525 5850);
DISPLAY 0.510638 (1525 5850);
DISPLAY INVISIBLE (1525 5850);
FORCEPROP 1 LAST VALUE 0.1UF
J 0
(1525 6050);
DISPLAY 0.510638 (1525 6050);
FORCEPROP 1 LAST VOLTAGE 25V
J 0
(1525 6000);
DISPLAY 0.510638 (1525 6000);
FORCEPROP 1 LAST MATERIAL X7R
J 0
(1525 5900);
DISPLAY 0.510638 (1525 5900);
FORCEPROP 1 LAST TOLERANCE 10%
J 0
(1525 5950);
DISPLAY 0.510638 (1525 5950);
FORCEPROP 1 LAST PACK_TYPE 0402
J 0
(1525 5800);
DISPLAY 0.510638 (1525 5800);
FORCEPROP 1 LAST $LOCATION C2376
J 0
(1525 6100);
DISPLAY 0.978723 (1525 6100);
FORCEPROP 1 LASTPIN (1475 6100) $PN 1
J 0
(1485 6080);
DISPLAY 0.787234 (1485 6080);
FORCEPROP 1 LASTPIN (1475 5900) $PN 2
J 0
(1485 5880);
DISPLAY 0.787234 (1485 5880);
FORCEPROP 2 LAST CDS_LIB pure_quanta
J 2
(1475 6000);
PAINT MONO (1475 6000);
DISPLAY INVISIBLE (1475 6000);
FORCEPROP 1 LAST PATH I241
J 0
(1525 6150);
DISPLAY 0.978723 (1525 6150);
PAINT WHITE (1525 6150);
DISPLAY INVISIBLE (1525 6150);
FORCEPROP 2 LAST CDS_LOCATION C2376
J 0
(1525 6200);
DISPLAY 1.021277 (1525 6200);
DISPLAY INVISIBLE (1525 6200);
FORCEPROP 2 LAST $SEC 1
J 0
(1525 6200);
DISPLAY 0.680851 (1525 6200);
PAINT MONO (1525 6200);
DISPLAY INVISIBLE (1525 6200);
FORCEPROP 2 LAST CDS_SEC 1
J 0
(1525 6200);
DISPLAY 1.021277 (1525 6200);
DISPLAY INVISIBLE (1525 6200);
FORCEADD UNIVERSAL_GND..1
(1475 5775);
FORCEPROP 3 LASTPIN (1475 5825) SIG_NAME GND\g
J 0
(1485 5835);
DISPLAY 0.659574 (1485 5835);
PAINT MONO (1485 5835);
DISPLAY INVISIBLE (1485 5835);
FORCEPROP 1 LAST HDL_POWER GND
J 1
(1500 5700);
DISPLAY 0.872340 (1500 5700);
PAINT GREEN (1500 5700);
DISPLAY INVISIBLE (1500 5700);
FORCEPROP 2 LAST CDS_LIB logical_power
J 0
(1475 5775);
PAINT MONO (1475 5775);
DISPLAY INVISIBLE (1475 5775);
FORCEPROP 1 LAST PATH I242
J 0
(1550 5775);
DISPLAY 0.872340 (1550 5775);
PAINT AQUA (1550 5775);
DISPLAY INVISIBLE (1550 5775);
FORCEADD 74LVC1G08W57..1
(875 5750);
FORCEPROP 1 LAST PART_NUMBER AL1G0008020
J 0
(750 5959);
DISPLAY 0.723404 (750 5959);
PAINT GREEN (750 5959);
DISPLAY INVISIBLE (750 5959);
FORCEPROP 1 LAST MATERIAL IC
J 0
(731 5907);
DISPLAY 0.723404 (731 5907);
PAINT GREEN (731 5907);
FORCEPROP 2 LAST VALUE 74LVC1G08W5-7
J 0
(750 6025);
DISPLAY 0.808511 (750 6025);
FORCEPROP 2 LAST PART_TYPE SMLF
J 0
(750 6175);
DISPLAY 1.021277 (750 6175);
FORCEPROP 1 LAST $LOCATION U334
J 0
(750 6106);
DISPLAY 0.723404 (750 6106);
PAINT GREEN (750 6106);
FORCEPROP 2 LASTPIN (575 5850) $PN 1
J 2
(565 5860);
DISPLAY 0.680851 (565 5860);
PAINT MONO (565 5860);
FORCEPROP 2 LASTPIN (575 5750) $PN 2
J 2
(565 5760);
DISPLAY 0.680851 (565 5760);
PAINT MONO (565 5760);
FORCEPROP 2 LASTPIN (575 5650) $PN 3
J 2
(565 5660);
DISPLAY 0.680851 (565 5660);
PAINT MONO (565 5660);
FORCEPROP 2 LASTPIN (1175 5850) $PN 5
J 0
(1185 5860);
DISPLAY 0.680851 (1185 5860);
PAINT MONO (1185 5860);
FORCEPROP 2 LASTPIN (1175 5700) $PN 4
J 0
(1185 5710);
DISPLAY 0.680851 (1185 5710);
PAINT MONO (1185 5710);
FORCEPROP 2 LAST CDS_LIB pure_quanta
J 0
(875 5750);
DISPLAY INVISIBLE (875 5750);
FORCEPROP 1 LAST NEEDS_NO_SIZE TRUE
J 0
(875 5750);
DISPLAY 0.723404 (875 5750);
PAINT GREEN (875 5750);
DISPLAY INVISIBLE (875 5750);
FORCEPROP 1 LAST CDS_LMAN_SYM_OUTLINE -150,150,150,-150
J 0
(875 5750);
DISPLAY 0.468085 (875 5750);
PAINT GREEN (875 5750);
DISPLAY INVISIBLE (875 5750);
FORCEPROP 1 LAST PATH I243
J 0
(875 5750);
DISPLAY 0.723404 (875 5750);
PAINT GREEN (875 5750);
DISPLAY INVISIBLE (875 5750);
FORCEPROP 0 LAST CDS_LOCATION U334
J 0
(500 6275);
DISPLAY 1.021277 (500 6275);
DISPLAY INVISIBLE (500 6275);
FORCEPROP 2 LAST $SEC 1
J 0
(500 6275);
DISPLAY 0.680851 (500 6275);
PAINT MONO (500 6275);
DISPLAY INVISIBLE (500 6275);
FORCEPROP 2 LAST CDS_SEC 1
J 0
(500 6275);
DISPLAY 1.021277 (500 6275);
DISPLAY INVISIBLE (500 6275);
FORCEADD UNIVERSAL_GND..1
(525 5525);
FORCEPROP 3 LASTPIN (525 5575) SIG_NAME GND\g
J 0
(535 5585);
DISPLAY 0.659574 (535 5585);
PAINT MONO (535 5585);
DISPLAY INVISIBLE (535 5585);
FORCEPROP 2 LAST CDS_LIB logical_power
J 0
(525 5525);
PAINT MONO (525 5525);
DISPLAY INVISIBLE (525 5525);
FORCEPROP 1 LAST HDL_POWER GND
J 1
(550 5450);
DISPLAY 0.872340 (550 5450);
PAINT GREEN (550 5450);
DISPLAY INVISIBLE (550 5450);
FORCEPROP 1 LAST PATH I244
J 0
(600 5525);
DISPLAY 0.872340 (600 5525);
PAINT AQUA (600 5525);
DISPLAY INVISIBLE (600 5525);
FORCEADD Q_RES..1
(-625 5850);
FORCEPROP 1 LAST PART_NUMBER CS03322FB03
J 0
(-750 5900);
DISPLAY 0.638298 (-750 5900);
DISPLAY INVISIBLE (-750 5900);
FORCEPROP 1 LAST PACK_TYPE 0402LF
J 0
(-325 5825);
DISPLAY 0.510638 (-325 5825);
FORCEPROP 1 LAST MATERIAL CHIP
J 0
(-850 5800);
DISPLAY 0.638298 (-850 5800);
FORCEPROP 1 LAST VALUE 33.2
J 2
(-450 5825);
DISPLAY 0.510638 (-450 5825);
FORCEPROP 1 LAST TOLERANCE 1%
J 0
(-425 5825);
DISPLAY 0.510638 (-425 5825);
FORCEPROP 1 LAST $LOCATION R4746
J 0
(-850 5850);
DISPLAY 0.638298 (-850 5850);
FORCEPROP 1 LASTPIN (-725 5850) $PN 1
J 0
(-713 5862);
DISPLAY 0.787234 (-713 5862);
PAINT MONO (-713 5862);
FORCEPROP 1 LASTPIN (-525 5850) $PN 2
J 0
(-563 5862);
DISPLAY 0.787234 (-563 5862);
PAINT MONO (-563 5862);
FORCEPROP 1 LAST WATTAGE 1/16W
J 2
(-425 5950);
DISPLAY 0.638298 (-425 5950);
DISPLAY INVISIBLE (-425 5950);
FORCEPROP 2 LAST CDS_LIB pure_quanta
J 0
(-625 5850);
DISPLAY INVISIBLE (-625 5850);
FORCEPROP 1 LAST PATH I245
J 0
(-675 6000);
DISPLAY 0.978723 (-675 6000);
PAINT WHITE (-675 6000);
DISPLAY INVISIBLE (-675 6000);
FORCEPROP 0 LAST CDS_LOCATION R4746
J 0
(-775 5900);
DISPLAY 1.021277 (-775 5900);
DISPLAY INVISIBLE (-775 5900);
FORCEPROP 0 LAST $SEC 1
J 0
(-775 5900);
DISPLAY 0.680851 (-775 5900);
PAINT MONO (-775 5900);
DISPLAY INVISIBLE (-775 5900);
FORCEPROP 0 LAST CDS_SEC 1
J 0
(-775 5900);
DISPLAY 1.021277 (-775 5900);
DISPLAY INVISIBLE (-775 5900);
FORCEADD OFFPAGE..1
(-1600 5850);
FORCEPROP 2 LAST $XR1 216 
J 0
(-2002 5850);
DISPLAY 0.638298 (-2002 5850);
PAINT MONO (-2002 5850);
FORCEPROP 2 LAST $XR0 158 
J 0
(-1882 5850);
DISPLAY 0.638298 (-1882 5850);
PAINT MONO (-1882 5850);
FORCEPROP 2 LAST CDS_LIB standard
J 0
(-1600 5850);
DISPLAY INVISIBLE (-1600 5850);
FORCEPROP 1 LAST OFFPAGE TRUE
J 0
(-1275 5725);
DISPLAY 0.872340 (-1275 5725);
PAINT GREEN (-1275 5725);
DISPLAY INVISIBLE (-1275 5725);
FORCEPROP 1 LAST COMMENT_BODY TRUE
J 0
(-1475 5750);
DISPLAY 0.872340 (-1475 5750);
PAINT GREEN (-1475 5750);
DISPLAY INVISIBLE (-1475 5750);
FORCEPROP 2 LAST PATH I246
J 0
(-1550 5925);
DISPLAY 1.021277 (-1550 5925);
DISPLAY INVISIBLE (-1550 5925);
FORCEADD Q_RES..1
(2100 5700);
FORCEPROP 1 LAST PART_NUMBER CS04992FB07
J 0
(2200 5675);
DISPLAY 0.404255 (2200 5675);
DISPLAY INVISIBLE (2200 5675);
FORCEPROP 1 LAST VALUE 49.9
J 2
(2325 5700);
DISPLAY 0.510638 (2325 5700);
FORCEPROP 1 LAST MATERIAL CHIP
J 0
(1950 5675);
DISPLAY 0.404255 (1950 5675);
FORCEPROP 1 LAST $LOCATION R4750
J 0
(1875 5700);
DISPLAY 0.638298 (1875 5700);
FORCEPROP 1 LASTPIN (2000 5700) $PN 1
J 0
(2012 5712);
DISPLAY 0.787234 (2012 5712);
PAINT MONO (2012 5712);
FORCEPROP 1 LASTPIN (2200 5700) $PN 2
J 0
(2162 5712);
DISPLAY 0.787234 (2162 5712);
PAINT MONO (2162 5712);
FORCEPROP 1 LAST WATTAGE 1/16W
J 2
(2400 5650);
DISPLAY 0.404255 (2400 5650);
DISPLAY INVISIBLE (2400 5650);
FORCEPROP 1 LAST TOLERANCE 1%
J 0
(2325 5700);
DISPLAY 0.510638 (2325 5700);
DISPLAY INVISIBLE (2325 5700);
FORCEPROP 1 LAST PACK_TYPE 0402LF
J 0
(2400 5700);
DISPLAY 0.510638 (2400 5700);
DISPLAY INVISIBLE (2400 5700);
FORCEPROP 1 LAST PATH I247
J 0
(2050 5850);
DISPLAY 0.978723 (2050 5850);
PAINT WHITE (2050 5850);
DISPLAY INVISIBLE (2050 5850);
FORCEPROP 2 LAST CDS_LIB pure_quanta
J 0
(2100 5700);
DISPLAY INVISIBLE (2100 5700);
FORCEPROP 0 LAST CDS_LOCATION R4750
J 0
(1875 5750);
DISPLAY 1.021277 (1875 5750);
DISPLAY INVISIBLE (1875 5750);
FORCEPROP 0 LAST $SEC 1
J 0
(1875 5750);
DISPLAY 0.680851 (1875 5750);
PAINT MONO (1875 5750);
DISPLAY INVISIBLE (1875 5750);
FORCEPROP 0 LAST CDS_SEC 1
J 0
(1875 5750);
DISPLAY 1.021277 (1875 5750);
DISPLAY INVISIBLE (1875 5750);
FORCEADD OFFPAGE..2
(3075 5700);
FORCEPROP 2 LAST $XR1 154 
J 0
(3384 5700);
DISPLAY 0.638298 (3384 5700);
PAINT MONO (3384 5700);
FORCEPROP 2 LAST $XR0 153 
J 0
(3264 5700);
DISPLAY 0.638298 (3264 5700);
PAINT MONO (3264 5700);
FORCEPROP 1 LAST OFFPAGE TRUE
J 0
(3400 5575);
DISPLAY 0.872340 (3400 5575);
PAINT GREEN (3400 5575);
DISPLAY INVISIBLE (3400 5575);
FORCEPROP 1 LAST COMMENT_BODY TRUE
J 0
(3030 5605);
DISPLAY 0.872340 (3030 5605);
PAINT GREEN (3030 5605);
DISPLAY INVISIBLE (3030 5605);
FORCEPROP 2 LAST PATH I248
J 0
(3250 5775);
DISPLAY 1.021277 (3250 5775);
DISPLAY INVISIBLE (3250 5775);
FORCEPROP 2 LAST CDS_LIB standard
J 0
(3075 5700);
DISPLAY INVISIBLE (3075 5700);
FORCEADD Q_RES..1
(-625 5750);
FORCEPROP 1 LAST PART_NUMBER CS03322FB03
J 0
(-750 5800);
DISPLAY 0.638298 (-750 5800);
DISPLAY INVISIBLE (-750 5800);
FORCEPROP 1 LAST MATERIAL CHIP
J 0
(-850 5700);
DISPLAY 0.638298 (-850 5700);
FORCEPROP 1 LAST VALUE 33.2
J 2
(-450 5725);
DISPLAY 0.510638 (-450 5725);
FORCEPROP 1 LAST TOLERANCE 1%
J 0
(-425 5725);
DISPLAY 0.510638 (-425 5725);
FORCEPROP 1 LAST PACK_TYPE 0402LF
J 0
(-325 5725);
DISPLAY 0.510638 (-325 5725);
FORCEPROP 1 LAST $LOCATION R4747
J 0
(-850 5750);
DISPLAY 0.638298 (-850 5750);
FORCEPROP 1 LASTPIN (-725 5750) $PN 1
J 0
(-713 5762);
DISPLAY 0.787234 (-713 5762);
PAINT MONO (-713 5762);
FORCEPROP 1 LASTPIN (-525 5750) $PN 2
J 0
(-563 5762);
DISPLAY 0.787234 (-563 5762);
PAINT MONO (-563 5762);
FORCEPROP 1 LAST PATH I249
J 0
(-675 5900);
DISPLAY 0.978723 (-675 5900);
PAINT WHITE (-675 5900);
DISPLAY INVISIBLE (-675 5900);
FORCEPROP 2 LAST CDS_LIB pure_quanta
J 0
(-625 5750);
DISPLAY INVISIBLE (-625 5750);
FORCEPROP 1 LAST WATTAGE 1/16W
J 2
(-425 5850);
DISPLAY 0.638298 (-425 5850);
DISPLAY INVISIBLE (-425 5850);
FORCEPROP 0 LAST CDS_LOCATION R4747
J 0
(-775 5800);
DISPLAY 1.021277 (-775 5800);
DISPLAY INVISIBLE (-775 5800);
FORCEPROP 0 LAST $SEC 1
J 0
(-775 5800);
DISPLAY 0.680851 (-775 5800);
PAINT MONO (-775 5800);
DISPLAY INVISIBLE (-775 5800);
FORCEPROP 0 LAST CDS_SEC 1
J 0
(-775 5800);
DISPLAY 1.021277 (-775 5800);
DISPLAY INVISIBLE (-775 5800);
FORCEADD OFFPAGE..1
(-1600 5750);
FORCEPROP 2 LAST $XR0 213 
J 0
(-1882 5750);
DISPLAY 0.638298 (-1882 5750);
PAINT MONO (-1882 5750);
FORCEPROP 2 LAST PATH I250
J 0
(-1550 5825);
DISPLAY 1.021277 (-1550 5825);
DISPLAY INVISIBLE (-1550 5825);
FORCEPROP 1 LAST COMMENT_BODY TRUE
J 0
(-1475 5650);
DISPLAY 0.872340 (-1475 5650);
PAINT GREEN (-1475 5650);
DISPLAY INVISIBLE (-1475 5650);
FORCEPROP 1 LAST OFFPAGE TRUE
J 0
(-1275 5625);
DISPLAY 0.872340 (-1275 5625);
PAINT GREEN (-1275 5625);
DISPLAY INVISIBLE (-1275 5625);
FORCEPROP 2 LAST CDS_LIB standard
J 0
(-1600 5750);
DISPLAY INVISIBLE (-1600 5750);
FORCEADD Q_RES..1
(1050 6450);
FORCEPROP 1 LAST PART_NUMBER CS00002JB13
J 0
(925 6525);
DISPLAY 0.638298 (925 6525);
DISPLAY INVISIBLE (925 6525);
FORCEPROP 1 LAST PACK_TYPE 0402LF
J 0
(1325 6450);
DISPLAY 0.638298 (1325 6450);
FORCEPROP 1 LAST MATERIAL EMPTY
J 0
(1200 6400);
DISPLAY 0.638298 (1200 6400);
PAINT RED (1200 6400);
FORCEPROP 1 LAST VALUE 0
J 2
(1225 6450);
DISPLAY 0.638298 (1225 6450);
FORCEPROP 1 LAST TOLERANCE 5%
J 0
(1250 6450);
DISPLAY 0.638298 (1250 6450);
FORCEPROP 1 LAST $LOCATION R4748
J 0
(850 6450);
DISPLAY 0.638298 (850 6450);
FORCEPROP 1 LASTPIN (950 6450) $PN 1
J 0
(962 6462);
DISPLAY 0.787234 (962 6462);
PAINT MONO (962 6462);
FORCEPROP 1 LASTPIN (1150 6450) $PN 2
J 0
(1112 6462);
DISPLAY 0.787234 (1112 6462);
PAINT MONO (1112 6462);
FORCEPROP 2 LAST CDS_LIB pure_quanta
J 0
(1050 6450);
DISPLAY INVISIBLE (1050 6450);
FORCEPROP 1 LAST PATH I253
J 0
(1000 6600);
DISPLAY 0.978723 (1000 6600);
PAINT WHITE (1000 6600);
DISPLAY INVISIBLE (1000 6600);
FORCEPROP 1 LAST WATTAGE 1/16W
J 2
(1225 6575);
DISPLAY 0.638298 (1225 6575);
DISPLAY INVISIBLE (1225 6575);
FORCEPROP 0 LAST CDS_LOCATION R4748
J 0
(1000 6550);
DISPLAY 1.021277 (1000 6550);
DISPLAY INVISIBLE (1000 6550);
FORCEPROP 0 LAST $SEC 1
J 0
(1000 6550);
DISPLAY 0.680851 (1000 6550);
PAINT MONO (1000 6550);
DISPLAY INVISIBLE (1000 6550);
FORCEPROP 0 LAST CDS_SEC 1
J 0
(1000 6550);
DISPLAY 1.021277 (1000 6550);
DISPLAY INVISIBLE (1000 6550);
FORCEADD Q_RES..1
(1100 5375);
FORCEPROP 1 LAST PART_NUMBER CS00002JB13
J 0
(975 5450);
DISPLAY 0.638298 (975 5450);
DISPLAY INVISIBLE (975 5450);
FORCEPROP 1 LAST MATERIAL EMPTY
J 0
(1250 5325);
DISPLAY 0.638298 (1250 5325);
PAINT RED (1250 5325);
FORCEPROP 1 LAST TOLERANCE 5%
J 0
(1300 5375);
DISPLAY 0.638298 (1300 5375);
FORCEPROP 1 LAST PACK_TYPE 0402LF
J 0
(1375 5375);
DISPLAY 0.638298 (1375 5375);
FORCEPROP 1 LAST VALUE 0
J 2
(1275 5375);
DISPLAY 0.638298 (1275 5375);
FORCEPROP 1 LAST $LOCATION R4749
J 0
(875 5375);
DISPLAY 0.638298 (875 5375);
FORCEPROP 1 LASTPIN (1000 5375) $PN 1
J 0
(1012 5387);
DISPLAY 0.787234 (1012 5387);
PAINT MONO (1012 5387);
FORCEPROP 1 LASTPIN (1200 5375) $PN 2
J 0
(1162 5387);
DISPLAY 0.787234 (1162 5387);
PAINT MONO (1162 5387);
FORCEPROP 2 LAST CDS_LIB pure_quanta
J 0
(1100 5375);
DISPLAY INVISIBLE (1100 5375);
FORCEPROP 1 LAST PATH I254
J 0
(1050 5525);
DISPLAY 0.978723 (1050 5525);
PAINT WHITE (1050 5525);
DISPLAY INVISIBLE (1050 5525);
FORCEPROP 1 LAST WATTAGE 1/16W
J 2
(1275 5500);
DISPLAY 0.638298 (1275 5500);
DISPLAY INVISIBLE (1275 5500);
FORCEPROP 0 LAST CDS_LOCATION R4749
J 0
(1050 5475);
DISPLAY 1.021277 (1050 5475);
DISPLAY INVISIBLE (1050 5475);
FORCEPROP 0 LAST $SEC 1
J 0
(1050 5475);
DISPLAY 0.680851 (1050 5475);
PAINT MONO (1050 5475);
DISPLAY INVISIBLE (1050 5475);
FORCEPROP 0 LAST CDS_SEC 1
J 0
(1050 5475);
DISPLAY 1.021277 (1050 5475);
DISPLAY INVISIBLE (1050 5475);
FORCEADD UNIVERSAL_POWER..1
(-350 6400);
FORCEPROP 3 LASTPIN (-350 6350) SIG_NAME P3V3_AUX\g
J 0
(-340 6360);
DISPLAY 0.659574 (-340 6360);
PAINT MONO (-340 6360);
DISPLAY INVISIBLE (-340 6360);
FORCEPROP 1 LAST HDL_POWER P3V3_AUX
J 1
(-350 6450);
DISPLAY 0.872340 (-350 6450);
PAINT GREEN (-350 6450);
FORCEPROP 2 LAST CDS_LIB logical_power
J 0
(-350 6400);
DISPLAY INVISIBLE (-350 6400);
FORCEPROP 1 LAST PATH I255
J 0
(-300 6425);
DISPLAY 0.872340 (-300 6425);
PAINT AQUA (-300 6425);
DISPLAY INVISIBLE (-300 6425);
FORCEADD Q_RES..2
(-350 6200);
FORCEPROP 1 LAST PART_NUMBER CS31002FB08
J 0
(-310 6075);
DISPLAY 0.787234 (-310 6075);
DISPLAY INVISIBLE (-310 6075);
FORCEPROP 1 LAST WATTAGE 1/16W
J 0
(-310 6175);
DISPLAY 0.787234 (-310 6175);
FORCEPROP 1 LAST TOLERANCE 1%
J 0
(-305 6225);
DISPLAY 0.787234 (-305 6225);
FORCEPROP 1 LAST MATERIAL CHIP
J 0
(-310 6125);
DISPLAY 0.787234 (-310 6125);
FORCEPROP 1 LAST PACK_TYPE 0402LF
J 0
(-310 6025);
DISPLAY 0.787234 (-310 6025);
FORCEPROP 1 LAST VALUE 10K
J 0
(-305 6275);
DISPLAY 0.787234 (-305 6275);
FORCEPROP 1 LAST $LOCATION R4745
J 0
(-305 6325);
DISPLAY 0.787234 (-305 6325);
FORCEPROP 1 LASTPIN (-350 6300) $PN 1
J 0
(-345 6262);
DISPLAY 0.787234 (-345 6262);
PAINT MONO (-345 6262);
FORCEPROP 1 LASTPIN (-350 6100) $PN 2
J 0
(-345 6110);
DISPLAY 0.787234 (-345 6110);
PAINT MONO (-345 6110);
FORCEPROP 2 LAST CDS_LIB pure_quanta
J 0
(-350 6200);
DISPLAY INVISIBLE (-350 6200);
FORCEPROP 1 LAST PATH I256
J 0
(-300 6375);
DISPLAY 0.978723 (-300 6375);
PAINT WHITE (-300 6375);
DISPLAY INVISIBLE (-300 6375);
FORCEPROP 0 LAST CDS_LOCATION R4745
J 0
(-300 6375);
DISPLAY 1.021277 (-300 6375);
DISPLAY INVISIBLE (-300 6375);
FORCEPROP 0 LAST $SEC 1
J 0
(-300 6375);
DISPLAY 0.680851 (-300 6375);
PAINT MONO (-300 6375);
DISPLAY INVISIBLE (-300 6375);
FORCEPROP 0 LAST CDS_SEC 1
J 0
(-300 6375);
DISPLAY 1.021277 (-300 6375);
DISPLAY INVISIBLE (-300 6375);
FORCEADD Q_RES..2
(-275 9875);
FORCEPROP 1 LAST PART_NUMBER CS31002FB08
J 0
(-235 9750);
DISPLAY 0.510638 (-235 9750);
DISPLAY INVISIBLE (-235 9750);
FORCEPROP 1 LAST TOLERANCE 1%
J 0
(-230 9900);
DISPLAY 0.510638 (-230 9900);
FORCEPROP 1 LAST WATTAGE 1/16W
J 0
(-235 9850);
DISPLAY 0.510638 (-235 9850);
FORCEPROP 1 LAST MATERIAL CHIP
J 0
(-235 9800);
DISPLAY 0.510638 (-235 9800);
FORCEPROP 1 LAST PACK_TYPE 0402LF
J 0
(-235 9700);
DISPLAY 0.510638 (-235 9700);
FORCEPROP 1 LAST VALUE 10K
J 0
(-230 9950);
DISPLAY 0.510638 (-230 9950);
FORCEPROP 1 LAST $LOCATION R4764
J 0
(-230 10000);
DISPLAY 0.978723 (-230 10000);
FORCEPROP 1 LASTPIN (-275 9975) $PN 1
J 0
(-270 9937);
DISPLAY 0.787234 (-270 9937);
PAINT MONO (-270 9937);
FORCEPROP 1 LASTPIN (-275 9775) $PN 2
J 0
(-270 9785);
DISPLAY 0.787234 (-270 9785);
PAINT MONO (-270 9785);
FORCEPROP 2 LAST CDS_LIB pure_quanta
J 0
(-275 9875);
DISPLAY INVISIBLE (-275 9875);
FORCEPROP 1 LAST PATH I257
J 0
(-225 10050);
DISPLAY 0.978723 (-225 10050);
PAINT WHITE (-225 10050);
DISPLAY INVISIBLE (-225 10050);
FORCEPROP 0 LAST CDS_LOCATION R4764
J 0
(-225 10050);
DISPLAY 1.021277 (-225 10050);
DISPLAY INVISIBLE (-225 10050);
FORCEPROP 0 LAST $SEC 1
J 0
(-225 10050);
DISPLAY 0.680851 (-225 10050);
PAINT MONO (-225 10050);
DISPLAY INVISIBLE (-225 10050);
FORCEPROP 0 LAST CDS_SEC 1
J 0
(-225 10050);
DISPLAY 1.021277 (-225 10050);
DISPLAY INVISIBLE (-225 10050);
FORCEADD UNIVERSAL_POWER..1
(-275 10100);
FORCEPROP 3 LASTPIN (-275 10050) SIG_NAME P3V3_AUX\g
J 0
(-265 10060);
DISPLAY 0.659574 (-265 10060);
PAINT MONO (-265 10060);
DISPLAY INVISIBLE (-265 10060);
FORCEPROP 1 LAST HDL_POWER P3V3_AUX
J 1
(-275 10150);
DISPLAY 0.872340 (-275 10150);
PAINT GREEN (-275 10150);
FORCEPROP 2 LAST CDS_LIB logical_power
J 0
(-275 10100);
DISPLAY INVISIBLE (-275 10100);
FORCEPROP 1 LAST PATH I258
J 0
(-225 10125);
DISPLAY 0.872340 (-225 10125);
PAINT AQUA (-225 10125);
DISPLAY INVISIBLE (-225 10125);
FORCEADD QUANTA_TITLE_BLOCK_C..1
(3975 3800);
FORCEPROP 0 LAST CDS_CON_LAST_MODIFIED Fri Aug 25 14:02:23 2023
J 0
(2090 3815);
PAINT MONO (2090 3815);
DISPLAY INVISIBLE (2090 3815);
FORCEPROP 2 LAST CUSTOM_TXT_CDS <XR_PAGE_TITLE>
J 0
(-3915 9050);
DISPLAY 0.638298 (-3915 9050);
PAINT PINK (-3915 9050);
DISPLAY INVISIBLE (-3915 9050);
FORCEPROP 2 LAST CUSTOM_TXT_CDS <CON_LAST_MODIFIED>
J 0
(2090 3815);
DISPLAY 0.978723 (2090 3815);
FORCEPROP 2 LAST CUSTOM_TXT_CDS <CON_PAGE_NUM> OF <CON_TOTAL_PAGES>
J 0
(3529 3818);
DISPLAY 0.978723 (3529 3818);
FORCEPROP 2 LAST CUSTOM_TXT_CDS <NAME_2>
J 0
(800 3850);
FORCEPROP 2 LAST CUSTOM_TXT_CDS <NAME_1>
J 0
(800 3975);
FORCEPROP 2 LAST CUSTOM_TXT_CDS <Q_PROJ>
J 0
(1593 3902);
DISPLAY 1.212766 (1593 3902);
FORCEPROP 2 LAST CUSTOM_TXT_CDS <Q_REV>
J 0
(3791 3903);
DISPLAY 1.212766 (3791 3903);
FORCEPROP 2 LAST CUSTOM_TXT_CDS <Q_NUMBER>
J 0
(2572 3903);
DISPLAY 1.212766 (2572 3903);
FORCEPROP 1 LAST Q_TITLE SFF_OCP3.0 HSC(3/3)
J 0
(-5291 3826);
DISPLAY 2.446809 (-5291 3826);
PAINT GREEN (-5291 3826);
FORCEPROP 1 LAST Q_DEPT 
J 1
(212 3849);
DISPLAY 1.957447 (212 3849);
PAINT GREEN (212 3849);
FORCEPROP 2 LAST CDS_XR_PAGE_TITLE CR-158 : @S9S_MB_2U_LIB.S9S_MB_2U(SCH_1):PAGE158
J 0
(-3915 9050);
DISPLAY 0.638298 (-3915 9050);
PAINT PINK (-3915 9050);
DISPLAY INVISIBLE (-3915 9050);
FORCEPROP 1 LAST COMMENT_BODY TRUE
J 0
(3987 3787);
DISPLAY 0.978723 (3987 3787);
PAINT GREEN (3987 3787);
DISPLAY INVISIBLE (3987 3787);
FORCEPROP 2 LAST PAGE_BORDER TRUE
J 0
(-3915 9050);
DISPLAY 0.638298 (-3915 9050);
PAINT PINK (-3915 9050);
DISPLAY INVISIBLE (-3915 9050);
FORCEPROP 1 LAST CDS_LMAN_SYM_OUTLINE -9475,6775,100,-125
J 0
(3975 3800);
DISPLAY 0.468085 (3975 3800);
PAINT GREEN (3975 3800);
DISPLAY INVISIBLE (3975 3800);
FORCEPROP 2 LAST CDS_LIB pure_quanta
J 0
(3975 3800);
PAINT MONO (3975 3800);
DISPLAY INVISIBLE (3975 3800);
FORCEADD DNS..2
(1075 6450);
PAINT RED (1075 6450);
FORCEPROP 2 LAST CDS_LIB mstr_misc
J 0
(1075 6450);
DISPLAY INVISIBLE (1075 6450);
FORCEPROP 1 LAST COMMENT_BODY TRUE
R 1
J 0
(1150 6225);
DISPLAY 0.872340 (1150 6225);
PAINT GREEN (1150 6225);
DISPLAY INVISIBLE (1150 6225);
FORCEADD DNS..2
(1125 5375);
PAINT RED (1125 5375);
FORCEPROP 2 LAST CDS_LIB mstr_misc
J 0
(1125 5375);
DISPLAY INVISIBLE (1125 5375);
FORCEPROP 1 LAST COMMENT_BODY TRUE
R 1
J 0
(1200 5150);
DISPLAY 0.872340 (1200 5150);
PAINT GREEN (1200 5150);
DISPLAY INVISIBLE (1200 5150);
FORCEADD DNS..2
(-1875 7550);
PAINT RED (-1875 7550);
FORCEPROP 2 LAST CDS_LIB mstr_misc
J 0
(-1875 7550);
DISPLAY INVISIBLE (-1875 7550);
FORCEPROP 1 LAST COMMENT_BODY TRUE
R 1
J 0
(-1800 7325);
DISPLAY 0.872340 (-1800 7325);
PAINT GREEN (-1800 7325);
DISPLAY INVISIBLE (-1800 7325);
FORCEADD DNS..2
(-4320 9595);
PAINT RED (-4320 9595);
FORCEPROP 2 LAST CDS_LIB mstr_misc
J 0
(-4320 9595);
PAINT MONO (-4320 9595);
DISPLAY INVISIBLE (-4320 9595);
FORCEPROP 1 LAST COMMENT_BODY TRUE
J 0
(-4320 9595);
DISPLAY INVISIBLE (-4320 9595);
FORCEADD DNS..2
(-4570 9595);
PAINT RED (-4570 9595);
FORCEPROP 1 LAST COMMENT_BODY TRUE
J 0
(-4570 9595);
DISPLAY INVISIBLE (-4570 9595);
FORCEPROP 2 LAST CDS_LIB mstr_misc
J 0
(-4570 9595);
PAINT MONO (-4570 9595);
DISPLAY INVISIBLE (-4570 9595);
FORCEADD DNS..2
(-4820 9595);
PAINT RED (-4820 9595);
FORCEPROP 1 LAST COMMENT_BODY TRUE
J 0
(-4820 9595);
DISPLAY INVISIBLE (-4820 9595);
FORCEPROP 2 LAST CDS_LIB mstr_misc
J 0
(-4820 9595);
PAINT MONO (-4820 9595);
DISPLAY INVISIBLE (-4820 9595);
FORCEADD DNS..2
(-1320 7795);
PAINT RED (-1320 7795);
FORCEPROP 2 LAST CDS_LIB mstr_misc
J 0
(-1320 7795);
PAINT MONO (-1320 7795);
DISPLAY INVISIBLE (-1320 7795);
FORCEPROP 1 LAST COMMENT_BODY TRUE
J 0
(-1320 7795);
DISPLAY INVISIBLE (-1320 7795);
WIRE 16 -1 (-275 10050)(-275 9975);
WIRE 16 -1 (-2475 10125)(-2475 10050);
WIRE 16 -1 (-350 6300)(-350 6350);
WIRE 16 -1 (-2350 5675)(-2350 5725);
WIRE 16 -1 (-2600 5675)(-2350 5675);
WIRE 16 -1 (-2350 5600)(-2350 5675);
WIRE 16 -1 (-4175 7325)(-4175 7425);
WIRE 16 -1 (-3850 7325)(-4175 7325);
WIRE 16 -1 (-4175 7250)(-4175 7325);
WIRE 16 -1 (1475 6225)(1475 6175);
WIRE 16 -1 (-1325 7975)(-1325 7900);
WIRE 16 -1 (425 7800)(425 7850);
WIRE 16 -1 (175 7800)(425 7800);
WIRE 16 -1 (425 7725)(425 7800);
WIRE 16 -1 (3175 7425)(3175 7475);
WIRE 16 -1 (2950 7425)(3175 7425);
WIRE 16 -1 (3175 7350)(3175 7425);
WIRE 16 -1 (-4825 9950)(-4825 9875);
WIRE 16 -1 (-4000 5550)(-4000 5675);
WIRE 16 -1 (1475 5900)(1475 5825);
WIRE 16 -1 (525 5650)(525 5575);
WIRE 16 -1 (525 5650)(575 5650);
WIRE 16 -1 (-475 7025)(-475 6950);
WIRE 16 -1 (-475 7025)(-425 7025);
WIRE 16 -1 (425 7525)(425 7450);
WIRE 16 -1 (3175 7150)(3175 7075);
WIRE 16 -1 (-4325 8900)(-4325 8825);
WIRE 16 -1 (-4575 8900)(-4575 8825);
WIRE 16 -1 (-4825 8900)(-4825 8825);
WIRE 16 -1 (-2475 9800)(-2475 9725);
WIRE 16 -1 (-1900 8675)(-1900 8850);
WIRE 16 -1 (-2350 5400)(-2350 5325);
WIRE 16 -1 (-3225 5025)(-3225 4950);
WIRE 16 -1 (-4000 4700)(-4000 4575);
WIRE 16 -1 (-2975 7425)(-2975 7350);
WIRE 16 -1 (-3100 7425)(-2975 7425);
WIRE 16 -1 (-4175 7050)(-4175 6975);
WIRE 16 -1 (2050 6875)(2050 6800);
WIRE 16 -1 (2050 6875)(2100 6875);
WIRE 16 2175 (-450 9675)(25 9675);
WIRE 16 2175 (25 10200)(25 9675);
WIRE 16 2175 (-450 10200)(-450 9675);
WIRE 16 2175 (-450 10200)(25 10200);
WIRE 16 -1 (-1050 9500)(-275 9500);
FORCEPROP 0 LAST CDS_PHYS_NET_NAME HP_OCP_V3_1_EN
J 0
(-460 9542);
PAINT MONO (-460 9542);
DISPLAY INVISIBLE (-460 9542);
FORCEPROP 2 LAST SIG_NAME HP_OCP_V3_1_EN
J 0
(-935 9510);
DISPLAY 0.553191 (-935 9510);
PAINT WHITE (-935 9510);
FORCEPROP 0 LAST $PHYS_NET_NAME RST_PCIE_M2_N
J 0
(-460 9589);
PAINT MONO (-460 9589);
DISPLAY INVISIBLE (-460 9589);
WIRE 16 -1 (-275 9500)(-50 9500);
WIRE 16 -1 (-275 9775)(-275 9500);
WIRE 16 -1 (-2475 10050)(-2475 10000);
WIRE 16 -1 (-1900 9650)(-1800 9650);
WIRE 16 -1 (-2475 10050)(-1900 10050);
WIRE 16 -1 (-1900 10050)(-1900 9650);
WIRE 16 -1 (-1050 9300)(-50 9300);
FORCEPROP 0 LAST CDS_PHYS_NET_NAME TP_PCA9555_0_P06
J 0
(-460 9342);
PAINT MONO (-460 9342);
DISPLAY INVISIBLE (-460 9342);
FORCEPROP 2 LAST SIG_NAME TP_PCA9555_0_P6
J 0
(-935 9310);
DISPLAY 0.553191 (-935 9310);
PAINT WHITE (-935 9310);
FORCEPROP 0 LAST $PHYS_NET_NAME RST_PCIE_M2_N
J 0
(-460 9389);
PAINT MONO (-460 9389);
DISPLAY INVISIBLE (-460 9389);
WIRE 16 -1 (-1050 9250)(-50 9250);
FORCEPROP 0 LAST CDS_PHYS_NET_NAME TP_PCA9555_0_P06
J 0
(-460 9292);
PAINT MONO (-460 9292);
DISPLAY INVISIBLE (-460 9292);
FORCEPROP 2 LAST SIG_NAME TP_PCA9555_0_P7
J 0
(-935 9260);
DISPLAY 0.553191 (-935 9260);
PAINT WHITE (-935 9260);
FORCEPROP 0 LAST $PHYS_NET_NAME RST_PCIE_M2_N
J 0
(-460 9339);
PAINT MONO (-460 9339);
DISPLAY INVISIBLE (-460 9339);
WIRE 16 -1 (-1050 9200)(-50 9200);
FORCEPROP 0 LAST CDS_PHYS_NET_NAME TP_PCA9555_0_P06
J 0
(-460 9242);
PAINT MONO (-460 9242);
DISPLAY INVISIBLE (-460 9242);
FORCEPROP 2 LAST SIG_NAME TP_PCA9555_0_P10
J 0
(-935 9210);
DISPLAY 0.553191 (-935 9210);
PAINT WHITE (-935 9210);
FORCEPROP 0 LAST $PHYS_NET_NAME RST_PCIE_M2_N
J 0
(-460 9289);
PAINT MONO (-460 9289);
DISPLAY INVISIBLE (-460 9289);
WIRE 16 -1 (-1050 9150)(-50 9150);
FORCEPROP 0 LAST CDS_PHYS_NET_NAME TP_PCA9555_0_P06
J 0
(-460 9192);
PAINT MONO (-460 9192);
DISPLAY INVISIBLE (-460 9192);
FORCEPROP 2 LAST SIG_NAME TP_PCA9555_0_P11
J 0
(-935 9160);
DISPLAY 0.553191 (-935 9160);
PAINT WHITE (-935 9160);
FORCEPROP 0 LAST $PHYS_NET_NAME RST_PCIE_M2_N
J 0
(-460 9239);
PAINT MONO (-460 9239);
DISPLAY INVISIBLE (-460 9239);
WIRE 16 -1 (-1050 9100)(-50 9100);
FORCEPROP 0 LAST CDS_PHYS_NET_NAME TP_PCA9555_0_P06
J 0
(-460 9142);
PAINT MONO (-460 9142);
DISPLAY INVISIBLE (-460 9142);
FORCEPROP 2 LAST SIG_NAME TP_PCA9555_0_P12
J 0
(-935 9110);
DISPLAY 0.553191 (-935 9110);
PAINT WHITE (-935 9110);
FORCEPROP 0 LAST $PHYS_NET_NAME RST_PCIE_M2_N
J 0
(-460 9189);
PAINT MONO (-460 9189);
DISPLAY INVISIBLE (-460 9189);
WIRE 16 -1 (-1050 9050)(-50 9050);
FORCEPROP 0 LAST CDS_PHYS_NET_NAME TP_PCA9555_0_P06
J 0
(-460 9092);
PAINT MONO (-460 9092);
DISPLAY INVISIBLE (-460 9092);
FORCEPROP 2 LAST SIG_NAME TP_PCA9555_0_P13
J 0
(-935 9060);
DISPLAY 0.553191 (-935 9060);
PAINT WHITE (-935 9060);
FORCEPROP 0 LAST $PHYS_NET_NAME RST_PCIE_M2_N
J 0
(-460 9139);
PAINT MONO (-460 9139);
DISPLAY INVISIBLE (-460 9139);
WIRE 16 -1 (-1050 9350)(-50 9350);
FORCEPROP 0 LAST CDS_PHYS_NET_NAME HP_LVC3_OCP_V3_1_FAULT_N
J 0
(-460 9392);
PAINT MONO (-460 9392);
DISPLAY INVISIBLE (-460 9392);
FORCEPROP 2 LAST SIG_NAME TP_PCA9555_0_P5
J 0
(-935 9360);
DISPLAY 0.553191 (-935 9360);
PAINT WHITE (-935 9360);
FORCEPROP 0 LAST $PHYS_NET_NAME RST_PCIE_M2_N
J 0
(-460 9439);
PAINT MONO (-460 9439);
DISPLAY INVISIBLE (-460 9439);
WIRE 16 -1 (-1050 9400)(-50 9400);
FORCEPROP 0 LAST CDS_PHYS_NET_NAME HP_LVC3_OCP_V3_1_PRSNT2_N
J 0
(-460 9442);
PAINT MONO (-460 9442);
DISPLAY INVISIBLE (-460 9442);
FORCEPROP 2 LAST SIG_NAME HP_LVC3_OCP_V3_1_PRSNT2_N
J 0
(-935 9410);
DISPLAY 0.553191 (-935 9410);
PAINT WHITE (-935 9410);
FORCEPROP 0 LAST $PHYS_NET_NAME RST_PCIE_M2_N
J 0
(-460 9489);
PAINT MONO (-460 9489);
DISPLAY INVISIBLE (-460 9489);
WIRE 16 -1 (-1050 9450)(-50 9450);
FORCEPROP 0 LAST CDS_PHYS_NET_NAME HP_LVC3_OCP_V3_1_ATTN_OUT_SW_N
J 0
(-460 9492);
PAINT MONO (-460 9492);
DISPLAY INVISIBLE (-460 9492);
FORCEPROP 2 LAST SIG_NAME HP_LVC3_OCP_V3_1_ATTN_OUT_SW_N
J 0
(-935 9460);
DISPLAY 0.553191 (-935 9460);
PAINT WHITE (-935 9460);
FORCEPROP 0 LAST $PHYS_NET_NAME RST_PCIE_M2_N
J 0
(-460 9539);
PAINT MONO (-460 9539);
DISPLAY INVISIBLE (-460 9539);
WIRE 16 -1 (-1050 9550)(-50 9550);
FORCEPROP 0 LAST CDS_PHYS_NET_NAME TP_PCA9555_0_P06
J 0
(-460 9592);
PAINT MONO (-460 9592);
DISPLAY INVISIBLE (-460 9592);
FORCEPROP 2 LAST SIG_NAME TP_PCA9555_0_P01
J 0
(-935 9560);
DISPLAY 0.553191 (-935 9560);
PAINT WHITE (-935 9560);
FORCEPROP 0 LAST $PHYS_NET_NAME RST_PCIE_M2_N
J 0
(-460 9639);
PAINT MONO (-460 9639);
DISPLAY INVISIBLE (-460 9639);
WIRE 16 -1 (-1050 9600)(-50 9600);
FORCEPROP 0 LAST CDS_PHYS_NET_NAME TP_PCA9555_0_P06
J 0
(-460 9642);
PAINT MONO (-460 9642);
DISPLAY INVISIBLE (-460 9642);
FORCEPROP 2 LAST SIG_NAME TP_PCA9555_0_P00
J 0
(-935 9610);
DISPLAY 0.553191 (-935 9610);
PAINT WHITE (-935 9610);
FORCEPROP 0 LAST $PHYS_NET_NAME RST_PCIE_M2_N
J 0
(-460 9689);
PAINT MONO (-460 9689);
DISPLAY INVISIBLE (-460 9689);
WIRE 16 -1 (-1050 9000)(-50 9000);
FORCEPROP 0 LAST CDS_PHYS_NET_NAME TP_PCA9555_0_P06
J 0
(-460 9042);
PAINT MONO (-460 9042);
DISPLAY INVISIBLE (-460 9042);
FORCEPROP 2 LAST SIG_NAME TP_PCA9555_0_P14
J 0
(-935 9010);
DISPLAY 0.553191 (-935 9010);
PAINT WHITE (-935 9010);
FORCEPROP 0 LAST $PHYS_NET_NAME RST_PCIE_M2_N
J 0
(-460 9089);
PAINT MONO (-460 9089);
DISPLAY INVISIBLE (-460 9089);
WIRE 16 -1 (-1050 8950)(-50 8950);
FORCEPROP 0 LAST CDS_PHYS_NET_NAME TP_PCA9555_0_P06
J 0
(-460 8992);
PAINT MONO (-460 8992);
DISPLAY INVISIBLE (-460 8992);
FORCEPROP 2 LAST SIG_NAME TP_PCA9555_0_P15
J 0
(-935 8960);
DISPLAY 0.553191 (-935 8960);
PAINT WHITE (-935 8960);
FORCEPROP 0 LAST $PHYS_NET_NAME RST_PCIE_M2_N
J 0
(-460 9039);
PAINT MONO (-460 9039);
DISPLAY INVISIBLE (-460 9039);
WIRE 16 -1 (-3900 8250)(-2900 8250);
FORCEPROP 0 LAST CDS_PHYS_NET_NAME SMB_PEHPCPU0_LVC3_SDA
J 0
(-3310 8292);
PAINT MONO (-3310 8292);
DISPLAY INVISIBLE (-3310 8292);
FORCEPROP 2 LAST SIG_NAME SMB_PEHPCPU0_LVC3_SDA
J 0
(-3785 8260);
DISPLAY 0.553191 (-3785 8260);
PAINT WHITE (-3785 8260);
FORCEPROP 0 LAST $PHYS_NET_NAME RST_PCIE_M2_N
J 0
(-3310 8339);
PAINT MONO (-3310 8339);
DISPLAY INVISIBLE (-3310 8339);
WIRE 16 -1 (475 5375)(1000 5375);
WIRE 16 -1 (475 5750)(475 5375);
WIRE 16 -1 (475 5750)(575 5750);
WIRE 16 -1 (-350 6100)(-350 5750);
WIRE 16 -1 (-350 5750)(475 5750);
FORCEPROP 2 LAST SIG_NAME OCP_SFF_AUX_PWR_PLD_EN_R
J 0
(-285 5760);
DISPLAY 0.553191 (-285 5760);
PAINT WHITE (-285 5760);
WIRE 16 -1 (-525 5750)(-350 5750);
FORCEPROP 0 LAST CDS_PHYS_NET_NAME HP_LVC3_OCP_V3_1_PWRGD
J 0
(-410 5792);
PAINT MONO (-410 5792);
DISPLAY INVISIBLE (-410 5792);
FORCEPROP 0 LAST $PHYS_NET_NAME RST_PCIE_M2_N
J 0
(-410 5839);
PAINT MONO (-410 5839);
DISPLAY INVISIBLE (-410 5839);
WIRE 16 2175 (-2025 6650)(3525 6650);
WIRE 16 2175 (3525 6650)(3525 5250);
WIRE 16 2175 (-2025 6650)(-2025 5250);
WIRE 16 2175 (-2025 5250)(3525 5250);
WIRE 16 -1 (1800 5375)(1200 5375);
WIRE 16 -1 (1175 5700)(1800 5700);
FORCEPROP 0 LAST CDS_PHYS_NET_NAME HP_LVC3_OCP_V3_1_PWRGD
J 0
(1290 5742);
PAINT MONO (1290 5742);
DISPLAY INVISIBLE (1290 5742);
FORCEPROP 2 LAST SIG_NAME OCP_SFF_AUX_PWR_EN_R2
J 0
(1240 5710);
DISPLAY 0.553191 (1240 5710);
PAINT WHITE (1240 5710);
FORCEPROP 0 LAST $PHYS_NET_NAME RST_PCIE_M2_N
J 0
(1290 5789);
PAINT MONO (1290 5789);
DISPLAY INVISIBLE (1290 5789);
WIRE 16 -1 (1800 5700)(1800 5375);
WIRE 16 -1 (1800 5700)(1825 5700);
WIRE 16 -1 (1825 5700)(2000 5700);
WIRE 16 -1 (1825 6450)(1825 5700);
WIRE 16 -1 (1150 6450)(1825 6450);
WIRE 16 -1 (1475 6100)(1475 6175);
WIRE 16 -1 (1350 6175)(1475 6175);
WIRE 16 -1 (1350 5850)(1350 6175);
WIRE 16 -1 (1175 5850)(1350 5850);
WIRE 16 -1 (-525 5850)(475 5850);
FORCEPROP 0 LAST CDS_PHYS_NET_NAME HP_LVC3_OCP_V3_1_PWRGD
J 0
(-410 5892);
PAINT MONO (-410 5892);
DISPLAY INVISIBLE (-410 5892);
FORCEPROP 2 LAST SIG_NAME HP_LVC3_OCP_V3_1_PWRGD_R2
J 0
(-285 5860);
DISPLAY 0.553191 (-285 5860);
PAINT WHITE (-285 5860);
FORCEPROP 0 LAST $PHYS_NET_NAME RST_PCIE_M2_N
J 0
(-410 5939);
PAINT MONO (-410 5939);
DISPLAY INVISIBLE (-410 5939);
WIRE 16 -1 (475 5850)(575 5850);
WIRE 16 -1 (475 5850)(475 6450);
WIRE 16 -1 (475 6450)(950 6450);
WIRE 16 -1 (2700 6925)(3450 6925);
FORCEPROP 0 LAST CDS_PHYS_NET_NAME RST_HP_OCP_V3_1_N
J 0
(3090 6967);
PAINT MONO (3090 6967);
DISPLAY INVISIBLE (3090 6967);
FORCEPROP 2 LAST SIG_NAME RST_HP_OCP_V3_1_N
J 0
(2815 6935);
DISPLAY 0.553191 (2815 6935);
PAINT WHITE (2815 6935);
FORCEPROP 0 LAST $PHYS_NET_NAME RST_PCIE_M2_N
J 0
(3090 7014);
PAINT MONO (3090 7014);
DISPLAY INVISIBLE (3090 7014);
WIRE 16 -1 (-2625 5075)(-1900 5075);
FORCEPROP 0 LAST CDS_PHYS_NET_NAME HP_LVC3_OCP_V3_1_EN
J 0
(-2260 5117);
PAINT MONO (-2260 5117);
DISPLAY INVISIBLE (-2260 5117);
FORCEPROP 2 LAST SIG_NAME HP_LVC3_OCP_V3_1_EN
J 0
(-2510 5085);
DISPLAY 0.553191 (-2510 5085);
PAINT WHITE (-2510 5085);
FORCEPROP 0 LAST $PHYS_NET_NAME RST_PCIE_M2_N
J 0
(-2260 5164);
PAINT MONO (-2260 5164);
DISPLAY INVISIBLE (-2260 5164);
WIRE 16 2175 (-4450 7625)(-3900 7625);
WIRE 16 2175 (-3900 7625)(-3900 7375);
WIRE 16 2175 (-4450 7625)(-4450 7375);
WIRE 16 2175 (-4450 7375)(-3900 7375);
WIRE 16 -1 (-1975 7225)(-3100 7225);
FORCEPROP 0 LAST CDS_PHYS_NET_NAME HP_LVC3_OCP_V3_1_HSC_PWRGD
J 0
(-2260 7267);
PAINT MONO (-2260 7267);
DISPLAY INVISIBLE (-2260 7267);
FORCEPROP 2 LAST SIG_NAME HP_OCP_V3_1_RST
J 0
(-2760 7235);
DISPLAY 0.446809 (-2760 7235);
PAINT WHITE (-2760 7235);
FORCEPROP 0 LAST $PHYS_NET_NAME RST_PCIE_M2_N
J 0
(-2260 7314);
PAINT MONO (-2260 7314);
DISPLAY INVISIBLE (-2260 7314);
WIRE 16 -1 (-725 5750)(-1550 5750);
FORCEPROP 0 LAST CDS_PHYS_NET_NAME HP_LVC3_OCP_V3_1_PWRGD
J 0
(-1435 5792);
PAINT MONO (-1435 5792);
DISPLAY INVISIBLE (-1435 5792);
FORCEPROP 2 LAST SIG_NAME OCP_SFF_AUX_PWR_PLD_EN
J 0
(-1560 5760);
DISPLAY 0.553191 (-1560 5760);
PAINT WHITE (-1560 5760);
FORCEPROP 0 LAST $PHYS_NET_NAME RST_PCIE_M2_N
J 0
(-1435 5839);
PAINT MONO (-1435 5839);
DISPLAY INVISIBLE (-1435 5839);
WIRE 16 -1 (-1550 5850)(-725 5850);
FORCEPROP 0 LAST CDS_PHYS_NET_NAME HP_LVC3_OCP_V3_1_PWRGD
J 0
(-1435 5892);
PAINT MONO (-1435 5892);
DISPLAY INVISIBLE (-1435 5892);
FORCEPROP 2 LAST SIG_NAME HP_LVC3_OCP_V3_1_PWRGD_R
J 0
(-1560 5860);
DISPLAY 0.553191 (-1560 5860);
PAINT WHITE (-1560 5860);
FORCEPROP 0 LAST $PHYS_NET_NAME RST_PCIE_M2_N
J 0
(-1435 5939);
PAINT MONO (-1435 5939);
DISPLAY INVISIBLE (-1435 5939);
WIRE 16 -1 (1275 7450)(1425 7450);
WIRE 16 -1 (1275 7075)(1275 7450);
WIRE 16 -1 (1275 7075)(2100 7075);
FORCEPROP 0 LAST CDS_PHYS_NET_NAME HP_LVC3_OCP_V3_1_PWRGD
J 0
(1390 7117);
PAINT MONO (1390 7117);
DISPLAY INVISIBLE (1390 7117);
FORCEPROP 2 LAST SIG_NAME HP_LVC3_OCP_V3_1_PWRGD_R
J 0
(1415 7085);
DISPLAY 0.553191 (1415 7085);
PAINT WHITE (1415 7085);
FORCEPROP 0 LAST $PHYS_NET_NAME RST_PCIE_M2_N
J 0
(1390 7164);
PAINT MONO (1390 7164);
DISPLAY INVISIBLE (1390 7164);
WIRE 16 -1 (1175 7075)(1275 7075);
WIRE 16 -1 (2200 5700)(3025 5700);
FORCEPROP 0 LAST CDS_PHYS_NET_NAME HP_LVC3_OCP_V3_1_PWRGD
J 0
(2315 5742);
PAINT MONO (2315 5742);
DISPLAY INVISIBLE (2315 5742);
FORCEPROP 2 LAST SIG_NAME OCP_SFF_AUX_PWR_EN
J 0
(2365 5710);
DISPLAY 0.553191 (2365 5710);
PAINT WHITE (2365 5710);
FORCEPROP 0 LAST $PHYS_NET_NAME RST_PCIE_M2_N
J 0
(2315 5789);
PAINT MONO (2315 5789);
DISPLAY INVISIBLE (2315 5789);
WIRE 16 -1 (-4825 9100)(-4825 9250);
WIRE 16 -1 (-4825 9250)(-4825 9500);
WIRE 16 -1 (-4825 9250)(-1800 9250);
FORCEPROP 0 LAST CDS_PHYS_NET_NAME PD_SMB_OCP1_HP_ADD2
J 0
(-2210 9292);
PAINT MONO (-2210 9292);
DISPLAY INVISIBLE (-2210 9292);
FORCEPROP 2 LAST SIG_NAME PD_SMB_OCP1_HP_ADD2
J 0
(-2685 9260);
DISPLAY 0.553191 (-2685 9260);
PAINT WHITE (-2685 9260);
FORCEPROP 0 LAST $PHYS_NET_NAME RST_PCIE_M2_N
J 0
(-2210 9339);
PAINT MONO (-2210 9339);
DISPLAY INVISIBLE (-2210 9339);
WIRE 16 -1 (-4575 9300)(-4575 9100);
WIRE 16 -1 (-4575 9500)(-4575 9300);
WIRE 16 -1 (-1800 9300)(-4575 9300);
FORCEPROP 0 LAST CDS_PHYS_NET_NAME PD_SMB_OCP1_HP_ADD1
J 0
(-2210 9342);
PAINT MONO (-2210 9342);
DISPLAY INVISIBLE (-2210 9342);
FORCEPROP 2 LAST SIG_NAME PD_SMB_OCP1_HP_ADD1
J 0
(-2685 9310);
DISPLAY 0.553191 (-2685 9310);
PAINT WHITE (-2685 9310);
FORCEPROP 0 LAST $PHYS_NET_NAME RST_PCIE_M2_N
J 0
(-2210 9389);
PAINT MONO (-2210 9389);
DISPLAY INVISIBLE (-2210 9389);
WIRE 16 -1 (-4325 9350)(-4325 9100);
WIRE 16 -1 (-4325 9500)(-4325 9350);
WIRE 16 -1 (-4325 9350)(-1800 9350);
FORCEPROP 0 LAST CDS_PHYS_NET_NAME PD_SMB_OCP1_HP_ADD0
J 0
(-2210 9392);
PAINT MONO (-2210 9392);
DISPLAY INVISIBLE (-2210 9392);
FORCEPROP 2 LAST SIG_NAME PD_SMB_OCP1_HP_ADD0
J 0
(-2685 9360);
DISPLAY 0.553191 (-2685 9360);
PAINT WHITE (-2685 9360);
FORCEPROP 0 LAST $PHYS_NET_NAME RST_PCIE_M2_N
J 0
(-2210 9439);
PAINT MONO (-2210 9439);
DISPLAY INVISIBLE (-2210 9439);
WIRE 16 -1 (-1800 9450)(-2800 9450);
FORCEPROP 0 LAST CDS_PHYS_NET_NAME FM_SMB_CPU0_ALERT
J 0
(-2360 9492);
PAINT MONO (-2360 9492);
DISPLAY INVISIBLE (-2360 9492);
FORCEPROP 2 LAST SIG_NAME FM_SMB_CPU0_ALERT
J 0
(-2685 9460);
DISPLAY 0.553191 (-2685 9460);
PAINT WHITE (-2685 9460);
FORCEPROP 0 LAST $PHYS_NET_NAME RST_PCIE_M2_N
J 0
(-2360 9539);
PAINT MONO (-2360 9539);
DISPLAY INVISIBLE (-2360 9539);
WIRE 16 -1 (-1050 8850)(-50 8850);
FORCEPROP 0 LAST CDS_PHYS_NET_NAME TP_PCA9555_0_P06
J 0
(-460 8892);
PAINT MONO (-460 8892);
DISPLAY INVISIBLE (-460 8892);
FORCEPROP 2 LAST SIG_NAME TP_PCA9555_0_P17
J 0
(-935 8860);
DISPLAY 0.553191 (-935 8860);
PAINT WHITE (-935 8860);
FORCEPROP 0 LAST $PHYS_NET_NAME RST_PCIE_M2_N
J 0
(-460 8939);
PAINT MONO (-460 8939);
DISPLAY INVISIBLE (-460 8939);
WIRE 16 -1 (975 7075)(175 7075);
FORCEPROP 0 LAST CDS_PHYS_NET_NAME HP_LVC3_OCP_V3_1_PWRGD
J 0
(390 7117);
PAINT MONO (390 7117);
DISPLAY INVISIBLE (390 7117);
FORCEPROP 2 LAST SIG_NAME HP_LVC3_OCP_V3_1_PWRGD
J 0
(265 7085);
DISPLAY 0.553191 (265 7085);
PAINT WHITE (265 7085);
FORCEPROP 0 LAST $PHYS_NET_NAME RST_PCIE_M2_N
J 0
(390 7164);
PAINT MONO (390 7164);
DISPLAY INVISIBLE (390 7164);
WIRE 16 -1 (-1150 7125)(-425 7125);
FORCEPROP 0 LAST CDS_PHYS_NET_NAME HP_LVC3_OCP_V3_1_HSC_PWRGD
J 0
(-710 7167);
PAINT MONO (-710 7167);
DISPLAY INVISIBLE (-710 7167);
FORCEPROP 2 LAST SIG_NAME HP_LVC3_OCP_V3_1_P12V_PWRGD
J 0
(-1060 7135);
DISPLAY 0.446809 (-1060 7135);
PAINT WHITE (-1060 7135);
FORCEPROP 0 LAST $PHYS_NET_NAME RST_PCIE_M2_N
J 0
(-710 7214);
PAINT MONO (-710 7214);
DISPLAY INVISIBLE (-710 7214);
WIRE 16 -1 (-3900 8300)(-2900 8300);
FORCEPROP 0 LAST CDS_PHYS_NET_NAME SMB_PEHPCPU0_LVC3_SCL
J 0
(-3310 8342);
PAINT MONO (-3310 8342);
DISPLAY INVISIBLE (-3310 8342);
FORCEPROP 2 LAST SIG_NAME SMB_PEHPCPU0_LVC3_SCL
J 0
(-3785 8310);
DISPLAY 0.553191 (-3785 8310);
PAINT WHITE (-3785 8310);
FORCEPROP 0 LAST $PHYS_NET_NAME RST_PCIE_M2_N
J 0
(-3310 8389);
PAINT MONO (-3310 8389);
DISPLAY INVISIBLE (-3310 8389);
WIRE 16 -1 (-2700 7550)(-2000 7550);
FORCEPROP 2 LAST SIG_NAME OCP_V3_1_P3V3_PWRGD
J 0
(-2660 7560);
DISPLAY 0.574468 (-2660 7560);
PAINT WHITE (-2660 7560);
WIRE 16 -1 (-2800 9100)(-1800 9100);
FORCEPROP 0 LAST CDS_PHYS_NET_NAME SMB_PEHPCPU0_LVC3_R_SDA
J 0
(-2360 9142);
PAINT MONO (-2360 9142);
DISPLAY INVISIBLE (-2360 9142);
FORCEPROP 2 LAST SIG_NAME SMB_PEHPCPU0_LVC3_R_SDA
J 0
(-2685 9110);
DISPLAY 0.553191 (-2685 9110);
PAINT WHITE (-2685 9110);
FORCEPROP 0 LAST $PHYS_NET_NAME RST_PCIE_M2_N
J 0
(-2360 9189);
PAINT MONO (-2360 9189);
DISPLAY INVISIBLE (-2360 9189);
WIRE 16 -1 (-1800 9000)(-2800 9000);
FORCEPROP 0 LAST CDS_PHYS_NET_NAME SMB_PEHPCPU0_LVC3_R_SCL
J 0
(-2360 9042);
PAINT MONO (-2360 9042);
DISPLAY INVISIBLE (-2360 9042);
FORCEPROP 2 LAST SIG_NAME SMB_PEHPCPU0_LVC3_R_SCL
J 0
(-2685 9010);
DISPLAY 0.553191 (-2685 9010);
PAINT WHITE (-2685 9010);
FORCEPROP 0 LAST $PHYS_NET_NAME RST_PCIE_M2_N
J 0
(-2360 9089);
PAINT MONO (-2360 9089);
DISPLAY INVISIBLE (-2360 9089);
WIRE 16 -1 (-4000 5000)(-4000 5125);
WIRE 16 -1 (-4000 5125)(-3225 5125);
FORCEPROP 0 LAST CDS_PHYS_NET_NAME HP_LVC3_OCP_V3_1_PRSNT2
J 0
(-3510 5167);
PAINT MONO (-3510 5167);
DISPLAY INVISIBLE (-3510 5167);
FORCEPROP 2 LAST SIG_NAME HP_LVC3_OCP_V3_1_PRSNT2
J 0
(-3910 5135);
DISPLAY 0.446809 (-3910 5135);
PAINT WHITE (-3910 5135);
FORCEPROP 0 LAST $PHYS_NET_NAME RST_PCIE_M2_N
J 0
(-3510 5214);
PAINT MONO (-3510 5214);
DISPLAY INVISIBLE (-3510 5214);
WIRE 16 -1 (-4000 5350)(-4000 5125);
WIRE 16 -1 (-4925 4800)(-4150 4800);
FORCEPROP 0 LAST CDS_PHYS_NET_NAME HP_LVC3_OCP_V3_1_PRSNT2_N
J 0
(-4435 4842);
PAINT MONO (-4435 4842);
DISPLAY INVISIBLE (-4435 4842);
FORCEPROP 2 LAST SIG_NAME HP_LVC3_OCP_V3_1_PRSNT2_N
J 0
(-4835 4810);
DISPLAY 0.446809 (-4835 4810);
PAINT WHITE (-4835 4810);
FORCEPROP 0 LAST $PHYS_NET_NAME RST_PCIE_M2_N
J 0
(-4435 4889);
PAINT MONO (-4435 4889);
DISPLAY INVISIBLE (-4435 4889);
WIRE 16 -1 (-3650 5225)(-3225 5225);
FORCEPROP 0 LAST CDS_PHYS_NET_NAME HP_OCP_V3_1_EN
J 0
(-3510 5267);
PAINT MONO (-3510 5267);
DISPLAY INVISIBLE (-3510 5267);
FORCEPROP 2 LAST SIG_NAME HP_OCP_V3_1_EN
J 0
(-3610 5235);
DISPLAY 0.446809 (-3610 5235);
PAINT WHITE (-3610 5235);
FORCEPROP 0 LAST $PHYS_NET_NAME RST_PCIE_M2_N
J 0
(-3510 5314);
PAINT MONO (-3510 5314);
DISPLAY INVISIBLE (-3510 5314);
WIRE 16 -1 (-1050 8900)(-50 8900);
FORCEPROP 0 LAST CDS_PHYS_NET_NAME TP_PCA9555_0_P06
J 0
(-460 8942);
PAINT MONO (-460 8942);
DISPLAY INVISIBLE (-460 8942);
FORCEPROP 2 LAST SIG_NAME TP_PCA9555_0_P16
J 0
(-935 8910);
DISPLAY 0.553191 (-935 8910);
PAINT WHITE (-935 8910);
FORCEPROP 0 LAST $PHYS_NET_NAME RST_PCIE_M2_N
J 0
(-460 8989);
PAINT MONO (-460 8989);
DISPLAY INVISIBLE (-460 8989);
WIRE 16 -1 (-3900 8200)(-2900 8200);
FORCEPROP 0 LAST CDS_PHYS_NET_NAME FM_SMB_CPU0_ALERT
J 0
(-3460 8242);
PAINT MONO (-3460 8242);
DISPLAY INVISIBLE (-3460 8242);
FORCEPROP 2 LAST SIG_NAME FM_SMB_CPU0_ALERT
J 0
(-3785 8210);
DISPLAY 0.553191 (-3785 8210);
PAINT WHITE (-3785 8210);
WIRE 16 -1 (1025 6975)(2100 6975);
FORCEPROP 0 LAST CDS_PHYS_NET_NAME RST_OCP_V3_1_N
J 0
(1815 7017);
PAINT MONO (1815 7017);
DISPLAY INVISIBLE (1815 7017);
FORCEPROP 2 LAST SIG_NAME RST_OCP_V3_1_N
J 0
(1290 6985);
DISPLAY 0.553191 (1290 6985);
PAINT WHITE (1290 6985);
FORCEPROP 0 LAST $PHYS_NET_NAME RST_PCIE_M2_N
J 0
(1815 7064);
PAINT MONO (1815 7064);
DISPLAY INVISIBLE (1815 7064);
WIRE 16 -1 (-1250 8200)(-2700 8200);
FORCEPROP 0 LAST CDS_PHYS_NET_NAME FM_SMB_PEHPCPU0_PCIE_ALERT_N
J 0
(-2550 8242);
PAINT MONO (-2550 8242);
DISPLAY INVISIBLE (-2550 8242);
FORCEPROP 0 LAST SIG_NAME FM_SMB_PEHPCPU0_PCIE_ALERT_N
J 0
(-2135 8210);
DISPLAY 0.553191 (-2135 8210);
PAINT WHITE (-2135 8210);
WIRE 16 -1 (-1250 8250)(-2700 8250);
FORCEPROP 0 LAST CDS_PHYS_NET_NAME SMB_PEHPCPU0_LVC3_R_SDA
J 0
(-1660 8292);
PAINT MONO (-1660 8292);
DISPLAY INVISIBLE (-1660 8292);
FORCEPROP 2 LAST SIG_NAME SMB_PEHPCPU0_LVC3_R_SDA
J 0
(-2135 8260);
DISPLAY 0.553191 (-2135 8260);
PAINT WHITE (-2135 8260);
FORCEPROP 0 LAST $PHYS_NET_NAME RST_PCIE_M2_N
J 0
(-1660 8339);
PAINT MONO (-1660 8339);
DISPLAY INVISIBLE (-1660 8339);
WIRE 16 -1 (-1250 8300)(-2700 8300);
FORCEPROP 0 LAST CDS_PHYS_NET_NAME SMB_PEHPCPU0_LVC3_R_SCL
J 0
(-1660 8342);
PAINT MONO (-1660 8342);
DISPLAY INVISIBLE (-1660 8342);
FORCEPROP 2 LAST SIG_NAME SMB_PEHPCPU0_LVC3_R_SCL
J 0
(-2135 8310);
DISPLAY 0.553191 (-2135 8310);
PAINT WHITE (-2135 8310);
FORCEPROP 0 LAST $PHYS_NET_NAME RST_PCIE_M2_N
J 0
(-1660 8389);
PAINT MONO (-1660 8389);
DISPLAY INVISIBLE (-1660 8389);
WIRE 16 -1 (-1800 7550)(-1325 7550);
WIRE 16 -1 (-1325 7700)(-1325 7550);
WIRE 16 -1 (-1325 7225)(-1775 7225);
WIRE 16 -1 (-1325 7550)(-1325 7225);
WIRE 16 -1 (-1325 7225)(-425 7225);
FORCEPROP 0 LAST CDS_PHYS_NET_NAME HP_LVC3_OCP_V3_1_HSC_PWRGD
J 0
(-935 7267);
PAINT MONO (-935 7267);
DISPLAY INVISIBLE (-935 7267);
FORCEPROP 2 LAST SIG_NAME HP_OCP_V3_1_RST_R
J 0
(-1060 7235);
DISPLAY 0.446809 (-1060 7235);
PAINT WHITE (-1060 7235);
FORCEPROP 0 LAST $PHYS_NET_NAME RST_PCIE_M2_N
J 0
(-935 7314);
PAINT MONO (-935 7314);
DISPLAY INVISIBLE (-935 7314);
WIRE 16 -1 (-1800 8850)(-1900 8850);
WIRE 16 -1 (-4825 9875)(-4825 9700);
WIRE 16 -1 (-4575 9875)(-4825 9875);
WIRE 16 -1 (-4575 9700)(-4575 9875);
WIRE 16 -1 (-4325 9875)(-4575 9875);
WIRE 16 -1 (-4325 9700)(-4325 9875);
WIRE 16 -1 (2950 7075)(2700 7075);
WIRE 16 -1 (2950 7425)(2950 7075);
WIRE 16 -1 (-2600 5225)(-2625 5225);
WIRE 16 -1 (-2600 5675)(-2600 5225);
WIRE 16 -1 (175 7225)(175 7800);
DOT 1 (-2475 10050);
DOT 1 (-275 9500);
DOT 1 (475 5750);
DOT 1 (1825 5700);
DOT 1 (475 5850);
DOT 1 (1800 5700);
DOT 1 (1475 6175);
DOT 1 (-4575 9300);
DOT 1 (-1325 7225);
DOT 1 (425 7800);
DOT 1 (3175 7425);
DOT 1 (1275 7075);
DOT 1 (-1325 7550);
DOT 1 (-4000 5125);
DOT 1 (-2350 5675);
DOT 1 (-4575 9875);
DOT 1 (-4325 9350);
DOT 1 (-4825 9875);
DOT 1 (-4825 9250);
DOT 1 (-350 5750);
DOT 1 (-4175 7325);
FORCENOTE
20210607 MODIFY FOR GT
(1250 8125) 0;
DISPLAY LEFT (1250 8125);
DISPLAY 2.510638 (1250 8125);
PAINT PINK (1250 8125);
FORCENOTE
PCA9554 ADDR: 0X40
(-4025 9825) 0;
DISPLAY LEFT (-4025 9825);
DISPLAY 1.595745 (-4025 9825);
PAINT SKYBLUE (-4025 9825);
FORCENOTE
20210607 MODIFY FOR GT
(-4750 4325) 0;
DISPLAY LEFT (-4750 4325);
DISPLAY 2.510638 (-4750 4325);
PAINT PINK (-4750 4325);
FORCENOTE
PUSH PULL OUTPUT
(-3775 7050) 0;
DISPLAY LEFT (-3775 7050);
DISPLAY 0.808511 (-3775 7050);
PAINT PINK (-3775 7050);
FORCENOTE
20220224 CHANGE TO P3V3_OCP_SFF
(-5100 7650) 0;
DISPLAY LEFT (-5100 7650);
DISPLAY 0.808511 (-5100 7650);
PAINT PINK (-5100 7650);
FORCENOTE
20220803 DESIGN CHANGE
(75 5175) 0;
DISPLAY LEFT (75 5175);
DISPLAY 1.276596 (75 5175);
PAINT PINK (75 5175);
FORCENOTE
20220804 ADD R4764
(50 9675) 0;
DISPLAY LEFT (50 9675);
DISPLAY 1.021277 (50 9675);
PAINT PINK (50 9675);
FORCENOTE
20210811 MODIFY FOR GT
(-1900 10250) 0;
DISPLAY LEFT (-1900 10250);
DISPLAY 2.510638 (-1900 10250);
PAINT PINK (-1900 10250);
QUIT
